G04 ================== begin FILE IDENTIFICATION RECORD ==================*
G04 Layout Name:  D:/<user>/Wistron_project/16316-1/gbr-0621/16316-1.brd*
G04 Film Name:    L8*
G04 File Format:  Gerber RS274X*
G04 File Origin:  Cadence Allegro 16.5-S056*
G04 Origin Date:  Wed Jun 21 09:32:19 2017*
G04 *
G04 Layer:  VIA CLASS/BOTTOM*
G04 Layer:  PIN/BOTTOM*
G04 Layer:  ETCH/BOTTOM*
G04 Layer:  DRAWING FORMAT/LAYER_PCB_STORY*
G04 Layer:  DRAWING FORMAT/LAYER_L8*
G04 *
G04 Offset:    (0.00 0.00)*
G04 Mirror:    No*
G04 Mode:      Positive*
G04 Rotation:  0*
G04 FullContactRelief:  No*
G04 UndefLineWidth:     6.00*
G04 ================== end FILE IDENTIFICATION RECORD ====================*
%FSLAX35Y35*MOIN*%
%IR0*IPPOS*OFA0.00000B0.00000*MIA0B0*SFA1.00000B1.00000*%
%AMMACRO45*
4,1,40,.011,.007,
.011,-.007,
.010939,-.007695,
.010759,-.008368,
.010464,-.009,
.010064,-.009571,
.009571,-.010064,
.009,-.010464,
.008368,-.010759,
.007695,-.010939,
.007,-.011,
-.007,-.011,
-.007695,-.010939,
-.008368,-.010759,
-.009,-.010464,
-.009571,-.010064,
-.010064,-.009571,
-.010464,-.009,
-.010759,-.008368,
-.010939,-.007695,
-.011,-.007,
-.011,.007,
-.010939,.007695,
-.010759,.008368,
-.010464,.009,
-.010064,.009571,
-.009571,.010064,
-.009,.010464,
-.008368,.010759,
-.007695,.010939,
-.007,.011,
.007,.011,
.007695,.010939,
.008368,.010759,
.009,.010464,
.009571,.010064,
.010064,.009571,
.010464,.009,
.010759,.008368,
.010939,.007695,
.011,.007,
0.0*
%
%ADD45MACRO45*%
%AMMACRO36*
4,1,40,-.017,-.013,
-.017,.013,
-.016939,.013695,
-.016759,.014368,
-.016464,.015,
-.016064,.015571,
-.015571,.016064,
-.015,.016464,
-.014368,.016759,
-.013695,.016939,
-.013,.017,
.013,.017,
.013695,.016939,
.014368,.016759,
.015,.016464,
.015571,.016064,
.016064,.015571,
.016464,.015,
.016759,.014368,
.016939,.013695,
.017,.013,
.017,-.013,
.016939,-.013695,
.016759,-.014368,
.016464,-.015,
.016064,-.015571,
.015571,-.016064,
.015,-.016464,
.014368,-.016759,
.013695,-.016939,
.013,-.017,
-.013,-.017,
-.013695,-.016939,
-.014368,-.016759,
-.015,-.016464,
-.015571,-.016064,
-.016064,-.015571,
-.016464,-.015,
-.016759,-.014368,
-.016939,-.013695,
-.017,-.013,
0.0*
%
%ADD36MACRO36*%
%AMMACRO28*
4,1,40,.013,-.017,
-.013,-.017,
-.013695,-.016939,
-.014368,-.016759,
-.015,-.016464,
-.015571,-.016064,
-.016064,-.015571,
-.016464,-.015,
-.016759,-.014368,
-.016939,-.013695,
-.017,-.013,
-.017,.013,
-.016939,.013695,
-.016759,.014368,
-.016464,.015,
-.016064,.015571,
-.015571,.016064,
-.015,.016464,
-.014368,.016759,
-.013695,.016939,
-.013,.017,
.013,.017,
.013695,.016939,
.014368,.016759,
.015,.016464,
.015571,.016064,
.016064,.015571,
.016464,.015,
.016759,.014368,
.016939,.013695,
.017,.013,
.017,-.013,
.016939,-.013695,
.016759,-.014368,
.016464,-.015,
.016064,-.015571,
.015571,-.016064,
.015,-.016464,
.014368,-.016759,
.013695,-.016939,
.013,-.017,
0.0*
%
%ADD28MACRO28*%
%ADD10C,.01*%
%ADD13C,.02*%
%ADD50C,.03*%
%AMMACRO30*
4,1,12,.07,.1525,
-.07,.1525,
-.07,.0725,
-.015,.0725,
-.015,-.0725,
-.025,-.0725,
-.025,-.1525,
.025,-.1525,
.025,-.0725,
.015,-.0725,
.015,.0725,
.07,.0725,
.07,.1525,
0.0*
%
%ADD30MACRO30*%
%ADD17C,.022*%
%ADD12C,.04*%
%AMMACRO53*
4,1,40,-.007,-.004,
-.007,.004,
-.00697,.004347,
-.006879,.004684,
-.006732,.005,
-.006532,.005286,
-.006286,.005532,
-.006,.005732,
-.005684,.005879,
-.005347,.00597,
-.005,.006,
.005,.006,
.005347,.00597,
.005684,.005879,
.006,.005732,
.006286,.005532,
.006532,.005286,
.006732,.005,
.006879,.004684,
.00697,.004347,
.007,.004,
.007,-.004,
.00697,-.004347,
.006879,-.004684,
.006732,-.005,
.006532,-.005286,
.006286,-.005532,
.006,-.005732,
.005684,-.005879,
.005347,-.00597,
.005,-.006,
-.005,-.006,
-.005347,-.00597,
-.005684,-.005879,
-.006,-.005732,
-.006286,-.005532,
-.006532,-.005286,
-.006732,-.005,
-.006879,-.004684,
-.00697,-.004347,
-.007,-.004,
0.0*
%
%ADD53MACRO53*%
%ADD18C,.024*%
%AMMACRO65*
4,1,40,-.004,.007,
.004,.007,
.004347,.00697,
.004684,.006879,
.005,.006732,
.005286,.006532,
.005532,.006286,
.005732,.006,
.005879,.005684,
.00597,.005347,
.006,.005,
.006,-.005,
.00597,-.005347,
.005879,-.005684,
.005732,-.006,
.005532,-.006286,
.005286,-.006532,
.005,-.006732,
.004684,-.006879,
.004347,-.00697,
.004,-.007,
-.004,-.007,
-.004347,-.00697,
-.004684,-.006879,
-.005,-.006732,
-.005286,-.006532,
-.005532,-.006286,
-.005732,-.006,
-.005879,-.005684,
-.00597,-.005347,
-.006,-.005,
-.006,.005,
-.00597,.005347,
-.005879,.005684,
-.005732,.006,
-.005532,.006286,
-.005286,.006532,
-.005,.006732,
-.004684,.006879,
-.004347,.00697,
-.004,.007,
0.0*
%
%ADD65MACRO65*%
%ADD14C,.034*%
%ADD51C,.026*%
%ADD63C,.018*%
%ADD11C,.028*%
%ADD67C,.029*%
%ADD23C,.048*%
%ADD20C,.078*%
%AMMACRO71*
4,1,40,.008,.014,
-.008,.014,
-.008695,.013939,
-.009368,.013759,
-.01,.013464,
-.010571,.013064,
-.011064,.012571,
-.011464,.012,
-.011759,.011368,
-.011939,.010695,
-.012,.01,
-.012,-.01,
-.011939,-.010695,
-.011759,-.011368,
-.011464,-.012,
-.011064,-.012571,
-.010571,-.013064,
-.01,-.013464,
-.009368,-.013759,
-.008695,-.013939,
-.008,-.014,
.008,-.014,
.008695,-.013939,
.009368,-.013759,
.01,-.013464,
.010571,-.013064,
.011064,-.012571,
.011464,-.012,
.011759,-.011368,
.011939,-.010695,
.012,-.01,
.012,.01,
.011939,.010695,
.011759,.011368,
.011464,.012,
.011064,.012571,
.010571,.013064,
.01,.013464,
.009368,.013759,
.008695,.013939,
.008,.014,
0.0*
%
%ADD71MACRO71*%
%AMMACRO68*
4,1,40,.0225,.007,
.022378,.008389,
.022018,.009736,
.021428,.011,
.020628,.012142,
.019642,.013128,
.0185,.013928,
.017236,.014518,
.015889,.014878,
.0145,.015,
-.0145,.015,
-.015889,.014878,
-.017236,.014518,
-.0185,.013928,
-.019642,.013128,
-.020628,.012142,
-.021428,.011,
-.022018,.009736,
-.022378,.008389,
-.0225,.007,
-.0225,-.007,
-.022378,-.008389,
-.022018,-.009736,
-.021428,-.011,
-.020628,-.012142,
-.019642,-.013128,
-.0185,-.013928,
-.017236,-.014518,
-.015889,-.014878,
-.0145,-.015,
.0145,-.015,
.015889,-.014878,
.017236,-.014518,
.0185,-.013928,
.019642,-.013128,
.020628,-.012142,
.021428,-.011,
.022018,-.009736,
.022378,-.008389,
.0225,-.007,
.0225,.007,
0.0*
%
%ADD68MACRO68*%
%AMMACRO74*
4,1,40,.007,-.0225,
.008389,-.022378,
.009736,-.022018,
.011,-.021428,
.012142,-.020628,
.013128,-.019642,
.013928,-.0185,
.014518,-.017236,
.014878,-.015889,
.015,-.0145,
.015,.0145,
.014878,.015889,
.014518,.017236,
.013928,.0185,
.013128,.019642,
.012142,.020628,
.011,.021428,
.009736,.022018,
.008389,.022378,
.007,.0225,
-.007,.0225,
-.008389,.022378,
-.009736,.022018,
-.011,.021428,
-.012142,.020628,
-.013128,.019642,
-.013928,.0185,
-.014518,.017236,
-.014878,.015889,
-.015,.0145,
-.015,-.0145,
-.014878,-.015889,
-.014518,-.017236,
-.013928,-.0185,
-.013128,-.019642,
-.012142,-.020628,
-.011,-.021428,
-.009736,-.022018,
-.008389,-.022378,
-.007,-.0225,
.007,-.0225,
0.0*
%
%ADD74MACRO74*%
%AMMACRO54*
4,1,40,.014,-.008,
.014,.008,
.013939,.008695,
.013759,.009368,
.013464,.01,
.013064,.010571,
.012571,.011064,
.012,.011464,
.011368,.011759,
.010695,.011939,
.01,.012,
-.01,.012,
-.010695,.011939,
-.011368,.011759,
-.012,.011464,
-.012571,.011064,
-.013064,.010571,
-.013464,.01,
-.013759,.009368,
-.013939,.008695,
-.014,.008,
-.014,-.008,
-.013939,-.008695,
-.013759,-.009368,
-.013464,-.01,
-.013064,-.010571,
-.012571,-.011064,
-.012,-.011464,
-.011368,-.011759,
-.010695,-.011939,
-.01,-.012,
.01,-.012,
.010695,-.011939,
.011368,-.011759,
.012,-.011464,
.012571,-.011064,
.013064,-.010571,
.013464,-.01,
.013759,-.009368,
.013939,-.008695,
.014,-.008,
0.0*
%
%ADD54MACRO54*%
%ADD21C,.099*%
%AMMACRO57*
4,1,40,.007,-.011,
-.007,-.011,
-.007695,-.010939,
-.008368,-.010759,
-.009,-.010464,
-.009571,-.010064,
-.010064,-.009571,
-.010464,-.009,
-.010759,-.008368,
-.010939,-.007695,
-.011,-.007,
-.011,.007,
-.010939,.007695,
-.010759,.008368,
-.010464,.009,
-.010064,.009571,
-.009571,.010064,
-.009,.010464,
-.008368,.010759,
-.007695,.010939,
-.007,.011,
.007,.011,
.007695,.010939,
.008368,.010759,
.009,.010464,
.009571,.010064,
.010064,.009571,
.010464,.009,
.010759,.008368,
.010939,.007695,
.011,.007,
.011,-.007,
.010939,-.007695,
.010759,-.008368,
.010464,-.009,
.010064,-.009571,
.009571,-.010064,
.009,-.010464,
.008368,-.010759,
.007695,-.010939,
.007,-.011,
0.0*
%
%ADD57MACRO57*%
%AMMACRO42*
4,1,40,-.011,-.007,
-.011,.007,
-.010939,.007695,
-.010759,.008368,
-.010464,.009,
-.010064,.009571,
-.009571,.010064,
-.009,.010464,
-.008368,.010759,
-.007695,.010939,
-.007,.011,
.007,.011,
.007695,.010939,
.008368,.010759,
.009,.010464,
.009571,.010064,
.010064,.009571,
.010464,.009,
.010759,.008368,
.010939,.007695,
.011,.007,
.011,-.007,
.010939,-.007695,
.010759,-.008368,
.010464,-.009,
.010064,-.009571,
.009571,-.010064,
.009,-.010464,
.008368,-.010759,
.007695,-.010939,
.007,-.011,
-.007,-.011,
-.007695,-.010939,
-.008368,-.010759,
-.009,-.010464,
-.009571,-.010064,
-.010064,-.009571,
-.010464,-.009,
-.010759,-.008368,
-.010939,-.007695,
-.011,-.007,
0.0*
%
%ADD42MACRO42*%
%AMMACRO25*
4,1,40,-.012,-.008,
-.012,.008,
-.011939,.008695,
-.011759,.009368,
-.011464,.01,
-.011064,.010571,
-.010571,.011064,
-.01,.011464,
-.009368,.011759,
-.008695,.011939,
-.008,.012,
.008,.012,
.008695,.011939,
.009368,.011759,
.01,.011464,
.010571,.011064,
.011064,.010571,
.011464,.01,
.011759,.009368,
.011939,.008695,
.012,.008,
.012,-.008,
.011939,-.008695,
.011759,-.009368,
.011464,-.01,
.011064,-.010571,
.010571,-.011064,
.01,-.011464,
.009368,-.011759,
.008695,-.011939,
.008,-.012,
-.008,-.012,
-.008695,-.011939,
-.009368,-.011759,
-.01,-.011464,
-.010571,-.011064,
-.011064,-.010571,
-.011464,-.01,
-.011759,-.009368,
-.011939,-.008695,
-.012,-.008,
0.0*
%
%ADD25MACRO25*%
%AMMACRO47*
4,1,40,-.008,.012,
.008,.012,
.008695,.011939,
.009368,.011759,
.01,.011464,
.010571,.011064,
.011064,.010571,
.011464,.01,
.011759,.009368,
.011939,.008695,
.012,.008,
.012,-.008,
.011939,-.008695,
.011759,-.009368,
.011464,-.01,
.011064,-.010571,
.010571,-.011064,
.01,-.011464,
.009368,-.011759,
.008695,-.011939,
.008,-.012,
-.008,-.012,
-.008695,-.011939,
-.009368,-.011759,
-.01,-.011464,
-.010571,-.011064,
-.011064,-.010571,
-.011464,-.01,
-.011759,-.009368,
-.011939,-.008695,
-.012,-.008,
-.012,.008,
-.011939,.008695,
-.011759,.009368,
-.011464,.01,
-.011064,.010571,
-.010571,.011064,
-.01,.011464,
-.009368,.011759,
-.008695,.011939,
-.008,.012,
0.0*
%
%ADD47MACRO47*%
%AMMACRO39*
4,1,40,-.013,.017,
.013,.017,
.013695,.016939,
.014368,.016759,
.015,.016464,
.015571,.016064,
.016064,.015571,
.016464,.015,
.016759,.014368,
.016939,.013695,
.017,.013,
.017,-.013,
.016939,-.013695,
.016759,-.014368,
.016464,-.015,
.016064,-.015571,
.015571,-.016064,
.015,-.016464,
.014368,-.016759,
.013695,-.016939,
.013,-.017,
-.013,-.017,
-.013695,-.016939,
-.014368,-.016759,
-.015,-.016464,
-.015571,-.016064,
-.016064,-.015571,
-.016464,-.015,
-.016759,-.014368,
-.016939,-.013695,
-.017,-.013,
-.017,.013,
-.016939,.013695,
-.016759,.014368,
-.016464,.015,
-.016064,.015571,
-.015571,.016064,
-.015,.016464,
-.014368,.016759,
-.013695,.016939,
-.013,.017,
0.0*
%
%ADD39MACRO39*%
%AMMACRO33*
4,1,40,.017,.013,
.017,-.013,
.016939,-.013695,
.016759,-.014368,
.016464,-.015,
.016064,-.015571,
.015571,-.016064,
.015,-.016464,
.014368,-.016759,
.013695,-.016939,
.013,-.017,
-.013,-.017,
-.013695,-.016939,
-.014368,-.016759,
-.015,-.016464,
-.015571,-.016064,
-.016064,-.015571,
-.016464,-.015,
-.016759,-.014368,
-.016939,-.013695,
-.017,-.013,
-.017,.013,
-.016939,.013695,
-.016759,.014368,
-.016464,.015,
-.016064,.015571,
-.015571,.016064,
-.015,.016464,
-.014368,.016759,
-.013695,.016939,
-.013,.017,
.013,.017,
.013695,.016939,
.014368,.016759,
.015,.016464,
.015571,.016064,
.016064,.015571,
.016464,.015,
.016759,.014368,
.016939,.013695,
.017,.013,
0.0*
%
%ADD33MACRO33*%
%AMMACRO76*
4,1,6,-.005,.0135,
-.005,.0065,
-.025,-.0135,
.025,-.0135,
.005,.0065,
.005,.0135,
-.005,.0135,
0.0*
%
%ADD76MACRO76*%
%AMMACRO15*
4,1,40,.013,-.023,
-.013,-.023,
-.013695,-.022939,
-.014368,-.022759,
-.015,-.022464,
-.015571,-.022064,
-.016064,-.021571,
-.016464,-.021,
-.016759,-.020368,
-.016939,-.019695,
-.017,-.019,
-.017,.019,
-.016939,.019695,
-.016759,.020368,
-.016464,.021,
-.016064,.021571,
-.015571,.022064,
-.015,.022464,
-.014368,.022759,
-.013695,.022939,
-.013,.023,
.013,.023,
.013695,.022939,
.014368,.022759,
.015,.022464,
.015571,.022064,
.016064,.021571,
.016464,.021,
.016759,.020368,
.016939,.019695,
.017,.019,
.017,-.019,
.016939,-.019695,
.016759,-.020368,
.016464,-.021,
.016064,-.021571,
.015571,-.022064,
.015,-.022464,
.014368,-.022759,
.013695,-.022939,
.013,-.023,
0.0*
%
%ADD15MACRO15*%
%AMMACRO58*
4,1,40,.007,-.011,
-.007,-.011,
-.007695,-.010939,
-.008368,-.010759,
-.009,-.010464,
-.009571,-.010064,
-.010064,-.009571,
-.010464,-.009,
-.010759,-.008368,
-.010939,-.007695,
-.011,-.007,
-.011,.007,
-.010939,.007695,
-.010759,.008368,
-.010464,.009,
-.010064,.009571,
-.009571,.010064,
-.009,.010464,
-.008368,.010759,
-.007695,.010939,
-.007,.011,
.007,.011,
.007695,.010939,
.008368,.010759,
.009,.010464,
.009571,.010064,
.010064,.009571,
.010464,.009,
.010759,.008368,
.010939,.007695,
.011,.007,
.011,-.007,
.010939,-.007695,
.010759,-.008368,
.010464,-.009,
.010064,-.009571,
.009571,-.010064,
.009,-.010464,
.008368,-.010759,
.007695,-.010939,
.007,-.011,
0.0*
%
%ADD58MACRO58*%
%AMMACRO43*
4,1,40,-.011,-.007,
-.011,.007,
-.010939,.007695,
-.010759,.008368,
-.010464,.009,
-.010064,.009571,
-.009571,.010064,
-.009,.010464,
-.008368,.010759,
-.007695,.010939,
-.007,.011,
.007,.011,
.007695,.010939,
.008368,.010759,
.009,.010464,
.009571,.010064,
.010064,.009571,
.010464,.009,
.010759,.008368,
.010939,.007695,
.011,.007,
.011,-.007,
.010939,-.007695,
.010759,-.008368,
.010464,-.009,
.010064,-.009571,
.009571,-.010064,
.009,-.010464,
.008368,-.010759,
.007695,-.010939,
.007,-.011,
-.007,-.011,
-.007695,-.010939,
-.008368,-.010759,
-.009,-.010464,
-.009571,-.010064,
-.010064,-.009571,
-.010464,-.009,
-.010759,-.008368,
-.010939,-.007695,
-.011,-.007,
0.0*
%
%ADD43MACRO43*%
%AMMACRO24*
4,1,40,-.012,-.008,
-.012,.008,
-.011939,.008695,
-.011759,.009368,
-.011464,.01,
-.011064,.010571,
-.010571,.011064,
-.01,.011464,
-.009368,.011759,
-.008695,.011939,
-.008,.012,
.008,.012,
.008695,.011939,
.009368,.011759,
.01,.011464,
.010571,.011064,
.011064,.010571,
.011464,.01,
.011759,.009368,
.011939,.008695,
.012,.008,
.012,-.008,
.011939,-.008695,
.011759,-.009368,
.011464,-.01,
.011064,-.010571,
.010571,-.011064,
.01,-.011464,
.009368,-.011759,
.008695,-.011939,
.008,-.012,
-.008,-.012,
-.008695,-.011939,
-.009368,-.011759,
-.01,-.011464,
-.010571,-.011064,
-.011064,-.010571,
-.011464,-.01,
-.011759,-.009368,
-.011939,-.008695,
-.012,-.008,
0.0*
%
%ADD24MACRO24*%
%AMMACRO46*
4,1,40,-.008,.012,
.008,.012,
.008695,.011939,
.009368,.011759,
.01,.011464,
.010571,.011064,
.011064,.010571,
.011464,.01,
.011759,.009368,
.011939,.008695,
.012,.008,
.012,-.008,
.011939,-.008695,
.011759,-.009368,
.011464,-.01,
.011064,-.010571,
.010571,-.011064,
.01,-.011464,
.009368,-.011759,
.008695,-.011939,
.008,-.012,
-.008,-.012,
-.008695,-.011939,
-.009368,-.011759,
-.01,-.011464,
-.010571,-.011064,
-.011064,-.010571,
-.011464,-.01,
-.011759,-.009368,
-.011939,-.008695,
-.012,-.008,
-.012,.008,
-.011939,.008695,
-.011759,.009368,
-.011464,.01,
-.011064,.010571,
-.010571,.011064,
-.01,.011464,
-.009368,.011759,
-.008695,.011939,
-.008,.012,
0.0*
%
%ADD46MACRO46*%
%AMMACRO40*
4,1,40,-.013,.017,
.013,.017,
.013695,.016939,
.014368,.016759,
.015,.016464,
.015571,.016064,
.016064,.015571,
.016464,.015,
.016759,.014368,
.016939,.013695,
.017,.013,
.017,-.013,
.016939,-.013695,
.016759,-.014368,
.016464,-.015,
.016064,-.015571,
.015571,-.016064,
.015,-.016464,
.014368,-.016759,
.013695,-.016939,
.013,-.017,
-.013,-.017,
-.013695,-.016939,
-.014368,-.016759,
-.015,-.016464,
-.015571,-.016064,
-.016064,-.015571,
-.016464,-.015,
-.016759,-.014368,
-.016939,-.013695,
-.017,-.013,
-.017,.013,
-.016939,.013695,
-.016759,.014368,
-.016464,.015,
-.016064,.015571,
-.015571,.016064,
-.015,.016464,
-.014368,.016759,
-.013695,.016939,
-.013,.017,
0.0*
%
%ADD40MACRO40*%
%AMMACRO34*
4,1,40,.017,.013,
.017,-.013,
.016939,-.013695,
.016759,-.014368,
.016464,-.015,
.016064,-.015571,
.015571,-.016064,
.015,-.016464,
.014368,-.016759,
.013695,-.016939,
.013,-.017,
-.013,-.017,
-.013695,-.016939,
-.014368,-.016759,
-.015,-.016464,
-.015571,-.016064,
-.016064,-.015571,
-.016464,-.015,
-.016759,-.014368,
-.016939,-.013695,
-.017,-.013,
-.017,.013,
-.016939,.013695,
-.016759,.014368,
-.016464,.015,
-.016064,.015571,
-.015571,.016064,
-.015,.016464,
-.014368,.016759,
-.013695,.016939,
-.013,.017,
.013,.017,
.013695,.016939,
.014368,.016759,
.015,.016464,
.015571,.016064,
.016064,.015571,
.016464,.015,
.016759,.014368,
.016939,.013695,
.017,.013,
0.0*
%
%ADD34MACRO34*%
%AMMACRO16*
4,1,40,.017,.019,
.017,-.019,
.016939,-.019695,
.016759,-.020368,
.016464,-.021,
.016064,-.021571,
.015571,-.022064,
.015,-.022464,
.014368,-.022759,
.013695,-.022939,
.013,-.023,
-.013,-.023,
-.013695,-.022939,
-.014368,-.022759,
-.015,-.022464,
-.015571,-.022064,
-.016064,-.021571,
-.016464,-.021,
-.016759,-.020368,
-.016939,-.019695,
-.017,-.019,
-.017,.019,
-.016939,.019695,
-.016759,.020368,
-.016464,.021,
-.016064,.021571,
-.015571,.022064,
-.015,.022464,
-.014368,.022759,
-.013695,.022939,
-.013,.023,
.013,.023,
.013695,.022939,
.014368,.022759,
.015,.022464,
.015571,.022064,
.016064,.021571,
.016464,.021,
.016759,.020368,
.016939,.019695,
.017,.019,
0.0*
%
%ADD16MACRO16*%
%ADD80R,.022X.04*%
%ADD78R,.06X.012*%
%ADD61R,.023X.04*%
%ADD48R,.012X.06*%
%ADD62R,.016X.032*%
%ADD29R,.05X.08*%
%AMMACRO64*
4,1,40,.007,.004,
.007,-.004,
.00697,-.004347,
.006879,-.004684,
.006732,-.005,
.006532,-.005286,
.006286,-.005532,
.006,-.005732,
.005684,-.005879,
.005347,-.00597,
.005,-.006,
-.005,-.006,
-.005347,-.00597,
-.005684,-.005879,
-.006,-.005732,
-.006286,-.005532,
-.006532,-.005286,
-.006732,-.005,
-.006879,-.004684,
-.00697,-.004347,
-.007,-.004,
-.007,.004,
-.00697,.004347,
-.006879,.004684,
-.006732,.005,
-.006532,.005286,
-.006286,.005532,
-.006,.005732,
-.005684,.005879,
-.005347,.00597,
-.005,.006,
.005,.006,
.005347,.00597,
.005684,.005879,
.006,.005732,
.006286,.005532,
.006532,.005286,
.006732,.005,
.006879,.004684,
.00697,.004347,
.007,.004,
0.0*
%
%ADD64MACRO64*%
%AMMACRO52*
4,1,40,.004,-.007,
-.004,-.007,
-.004347,-.00697,
-.004684,-.006879,
-.005,-.006732,
-.005286,-.006532,
-.005532,-.006286,
-.005732,-.006,
-.005879,-.005684,
-.00597,-.005347,
-.006,-.005,
-.006,.005,
-.00597,.005347,
-.005879,.005684,
-.005732,.006,
-.005532,.006286,
-.005286,.006532,
-.005,.006732,
-.004684,.006879,
-.004347,.00697,
-.004,.007,
.004,.007,
.004347,.00697,
.004684,.006879,
.005,.006732,
.005286,.006532,
.005532,.006286,
.005732,.006,
.005879,.005684,
.00597,.005347,
.006,.005,
.006,-.005,
.00597,-.005347,
.005879,-.005684,
.005732,-.006,
.005532,-.006286,
.005286,-.006532,
.005,-.006732,
.004684,-.006879,
.004347,-.00697,
.004,-.007,
0.0*
%
%ADD52MACRO52*%
%ADD75R,.05X.065*%
%ADD41R,.065X.05*%
%ADD79R,.065X.025*%
%ADD72R,.048X.016*%
%ADD70R,.025X.065*%
%ADD26R,.045X.055*%
%ADD56R,.055X.045*%
%AMMACRO19*
4,1,25,-.26575,.30715,
-.209725,.333219,
-.150024,.349164,
-.088461,.3545,
-.026908,.349064,
.032767,.333022,
.08875,.306861,
.139339,.271377,
.182998,.227647,
.2184,.177,
.244469,.120975,
.260414,.061274,
.26575,-.000289,
.260314,-.061842,
.244272,-.121517,
.218111,-.1775,
.182627,-.228089,
.138897,-.271748,
.08825,-.30715,
.032225,-.333219,
-.027476,-.349164,
-.089039,-.3545,
-.150592,-.349064,
-.210267,-.333022,
-.26575,-.30715,
-.26575,.30715,
0.0*
%
%ADD19MACRO19*%
%AMMACRO81*
4,1,25,.26575,.30715,
.209725,.333219,
.150024,.349164,
.088461,.3545,
.026908,.349064,
-.032767,.333022,
-.08875,.306861,
-.139339,.271377,
-.182998,.227647,
-.2184,.177,
-.244469,.120975,
-.260414,.061274,
-.26575,-.000289,
-.260314,-.061842,
-.244272,-.121517,
-.218111,-.1775,
-.182627,-.228089,
-.138897,-.271748,
-.08825,-.30715,
-.032225,-.333219,
.027476,-.349164,
.089039,-.3545,
.150592,-.349064,
.210267,-.333022,
.26575,-.30715,
.26575,.30715,
0.0*
%
%ADD81MACRO81*%
%ADD49C,.375*%
%AMMACRO73*
4,1,40,-.007,.0225,
-.008389,.022378,
-.009736,.022018,
-.011,.021428,
-.012142,.020628,
-.013128,.019642,
-.013928,.0185,
-.014518,.017236,
-.014878,.015889,
-.015,.0145,
-.015,-.0145,
-.014878,-.015889,
-.014518,-.017236,
-.013928,-.0185,
-.013128,-.019642,
-.012142,-.020628,
-.011,-.021428,
-.009736,-.022018,
-.008389,-.022378,
-.007,-.0225,
.007,-.0225,
.008389,-.022378,
.009736,-.022018,
.011,-.021428,
.012142,-.020628,
.013128,-.019642,
.013928,-.0185,
.014518,-.017236,
.014878,-.015889,
.015,-.0145,
.015,.0145,
.014878,.015889,
.014518,.017236,
.013928,.0185,
.013128,.019642,
.012142,.020628,
.011,.021428,
.009736,.022018,
.008389,.022378,
.007,.0225,
-.007,.0225,
0.0*
%
%ADD73MACRO73*%
%AMMACRO69*
4,1,40,-.0225,-.007,
-.022378,-.008389,
-.022018,-.009736,
-.021428,-.011,
-.020628,-.012142,
-.019642,-.013128,
-.0185,-.013928,
-.017236,-.014518,
-.015889,-.014878,
-.0145,-.015,
.0145,-.015,
.015889,-.014878,
.017236,-.014518,
.0185,-.013928,
.019642,-.013128,
.020628,-.012142,
.021428,-.011,
.022018,-.009736,
.022378,-.008389,
.0225,-.007,
.0225,.007,
.022378,.008389,
.022018,.009736,
.021428,.011,
.020628,.012142,
.019642,.013128,
.0185,.013928,
.017236,.014518,
.015889,.014878,
.0145,.015,
-.0145,.015,
-.015889,.014878,
-.017236,.014518,
-.0185,.013928,
-.019642,.013128,
-.020628,.012142,
-.021428,.011,
-.022018,.009736,
-.022378,.008389,
-.0225,.007,
-.0225,-.007,
0.0*
%
%ADD69MACRO69*%
%AMMACRO66*
4,1,40,-.008,-.014,
.008,-.014,
.008695,-.013939,
.009368,-.013759,
.01,-.013464,
.010571,-.013064,
.011064,-.012571,
.011464,-.012,
.011759,-.011368,
.011939,-.010695,
.012,-.01,
.012,.01,
.011939,.010695,
.011759,.011368,
.011464,.012,
.011064,.012571,
.010571,.013064,
.01,.013464,
.009368,.013759,
.008695,.013939,
.008,.014,
-.008,.014,
-.008695,.013939,
-.009368,.013759,
-.01,.013464,
-.010571,.013064,
-.011064,.012571,
-.011464,.012,
-.011759,.011368,
-.011939,.010695,
-.012,.01,
-.012,-.01,
-.011939,-.010695,
-.011759,-.011368,
-.011464,-.012,
-.011064,-.012571,
-.010571,-.013064,
-.01,-.013464,
-.009368,-.013759,
-.008695,-.013939,
-.008,-.014,
0.0*
%
%ADD66MACRO66*%
%AMMACRO55*
4,1,40,-.014,.008,
-.014,-.008,
-.013939,-.008695,
-.013759,-.009368,
-.013464,-.01,
-.013064,-.010571,
-.012571,-.011064,
-.012,-.011464,
-.011368,-.011759,
-.010695,-.011939,
-.01,-.012,
.01,-.012,
.010695,-.011939,
.011368,-.011759,
.012,-.011464,
.012571,-.011064,
.013064,-.010571,
.013464,-.01,
.013759,-.009368,
.013939,-.008695,
.014,-.008,
.014,.008,
.013939,.008695,
.013759,.009368,
.013464,.01,
.013064,.010571,
.012571,.011064,
.012,.011464,
.011368,.011759,
.010695,.011939,
.01,.012,
-.01,.012,
-.010695,.011939,
-.011368,.011759,
-.012,.011464,
-.012571,.011064,
-.013064,.010571,
-.013464,.01,
-.013759,.009368,
-.013939,.008695,
-.014,.008,
0.0*
%
%ADD55MACRO55*%
%ADD22R,.272X.272*%
%AMMACRO59*
4,1,40,-.007,.011,
.007,.011,
.007695,.010939,
.008368,.010759,
.009,.010464,
.009571,.010064,
.010064,.009571,
.010464,.009,
.010759,.008368,
.010939,.007695,
.011,.007,
.011,-.007,
.010939,-.007695,
.010759,-.008368,
.010464,-.009,
.010064,-.009571,
.009571,-.010064,
.009,-.010464,
.008368,-.010759,
.007695,-.010939,
.007,-.011,
-.007,-.011,
-.007695,-.010939,
-.008368,-.010759,
-.009,-.010464,
-.009571,-.010064,
-.010064,-.009571,
-.010464,-.009,
-.010759,-.008368,
-.010939,-.007695,
-.011,-.007,
-.011,.007,
-.010939,.007695,
-.010759,.008368,
-.010464,.009,
-.010064,.009571,
-.009571,.010064,
-.009,.010464,
-.008368,.010759,
-.007695,.010939,
-.007,.011,
0.0*
%
%ADD59MACRO59*%
%AMMACRO38*
4,1,40,.008,-.012,
-.008,-.012,
-.008695,-.011939,
-.009368,-.011759,
-.01,-.011464,
-.010571,-.011064,
-.011064,-.010571,
-.011464,-.01,
-.011759,-.009368,
-.011939,-.008695,
-.012,-.008,
-.012,.008,
-.011939,.008695,
-.011759,.009368,
-.011464,.01,
-.011064,.010571,
-.010571,.011064,
-.01,.011464,
-.009368,.011759,
-.008695,.011939,
-.008,.012,
.008,.012,
.008695,.011939,
.009368,.011759,
.01,.011464,
.010571,.011064,
.011064,.010571,
.011464,.01,
.011759,.009368,
.011939,.008695,
.012,.008,
.012,-.008,
.011939,-.008695,
.011759,-.009368,
.011464,-.01,
.011064,-.010571,
.010571,-.011064,
.01,-.011464,
.009368,-.011759,
.008695,-.011939,
.008,-.012,
0.0*
%
%ADD38MACRO38*%
%AMMACRO32*
4,1,40,.012,.008,
.012,-.008,
.011939,-.008695,
.011759,-.009368,
.011464,-.01,
.011064,-.010571,
.010571,-.011064,
.01,-.011464,
.009368,-.011759,
.008695,-.011939,
.008,-.012,
-.008,-.012,
-.008695,-.011939,
-.009368,-.011759,
-.01,-.011464,
-.010571,-.011064,
-.011064,-.010571,
-.011464,-.01,
-.011759,-.009368,
-.011939,-.008695,
-.012,-.008,
-.012,.008,
-.011939,.008695,
-.011759,.009368,
-.011464,.01,
-.011064,.010571,
-.010571,.011064,
-.01,.011464,
-.009368,.011759,
-.008695,.011939,
-.008,.012,
.008,.012,
.008695,.011939,
.009368,.011759,
.01,.011464,
.010571,.011064,
.011064,.010571,
.011464,.01,
.011759,.009368,
.011939,.008695,
.012,.008,
0.0*
%
%ADD32MACRO32*%
%AMMACRO44*
4,1,40,.011,.007,
.011,-.007,
.010939,-.007695,
.010759,-.008368,
.010464,-.009,
.010064,-.009571,
.009571,-.010064,
.009,-.010464,
.008368,-.010759,
.007695,-.010939,
.007,-.011,
-.007,-.011,
-.007695,-.010939,
-.008368,-.010759,
-.009,-.010464,
-.009571,-.010064,
-.010064,-.009571,
-.010464,-.009,
-.010759,-.008368,
-.010939,-.007695,
-.011,-.007,
-.011,.007,
-.010939,.007695,
-.010759,.008368,
-.010464,.009,
-.010064,.009571,
-.009571,.010064,
-.009,.010464,
-.008368,.010759,
-.007695,.010939,
-.007,.011,
.007,.011,
.007695,.010939,
.008368,.010759,
.009,.010464,
.009571,.010064,
.010064,.009571,
.010464,.009,
.010759,.008368,
.010939,.007695,
.011,.007,
0.0*
%
%ADD44MACRO44*%
%AMMACRO77*
4,1,6,-.025,.0135,
-.005,-.0065,
-.005,-.0135,
.005,-.0135,
.005,-.0065,
.025,.0135,
-.025,.0135,
0.0*
%
%ADD77MACRO77*%
%AMMACRO35*
4,1,40,-.017,-.013,
-.017,.013,
-.016939,.013695,
-.016759,.014368,
-.016464,.015,
-.016064,.015571,
-.015571,.016064,
-.015,.016464,
-.014368,.016759,
-.013695,.016939,
-.013,.017,
.013,.017,
.013695,.016939,
.014368,.016759,
.015,.016464,
.015571,.016064,
.016064,.015571,
.016464,.015,
.016759,.014368,
.016939,.013695,
.017,.013,
.017,-.013,
.016939,-.013695,
.016759,-.014368,
.016464,-.015,
.016064,-.015571,
.015571,-.016064,
.015,-.016464,
.014368,-.016759,
.013695,-.016939,
.013,-.017,
-.013,-.017,
-.013695,-.016939,
-.014368,-.016759,
-.015,-.016464,
-.015571,-.016064,
-.016064,-.015571,
-.016464,-.015,
-.016759,-.014368,
-.016939,-.013695,
-.017,-.013,
0.0*
%
%ADD35MACRO35*%
%AMMACRO27*
4,1,40,.013,-.017,
-.013,-.017,
-.013695,-.016939,
-.014368,-.016759,
-.015,-.016464,
-.015571,-.016064,
-.016064,-.015571,
-.016464,-.015,
-.016759,-.014368,
-.016939,-.013695,
-.017,-.013,
-.017,.013,
-.016939,.013695,
-.016759,.014368,
-.016464,.015,
-.016064,.015571,
-.015571,.016064,
-.015,.016464,
-.014368,.016759,
-.013695,.016939,
-.013,.017,
.013,.017,
.013695,.016939,
.014368,.016759,
.015,.016464,
.015571,.016064,
.016064,.015571,
.016464,.015,
.016759,.014368,
.016939,.013695,
.017,.013,
.017,-.013,
.016939,-.013695,
.016759,-.014368,
.016464,-.015,
.016064,-.015571,
.015571,-.016064,
.015,-.016464,
.014368,-.016759,
.013695,-.016939,
.013,-.017,
0.0*
%
%ADD27MACRO27*%
%AMMACRO60*
4,1,40,-.007,.011,
.007,.011,
.007695,.010939,
.008368,.010759,
.009,.010464,
.009571,.010064,
.010064,.009571,
.010464,.009,
.010759,.008368,
.010939,.007695,
.011,.007,
.011,-.007,
.010939,-.007695,
.010759,-.008368,
.010464,-.009,
.010064,-.009571,
.009571,-.010064,
.009,-.010464,
.008368,-.010759,
.007695,-.010939,
.007,-.011,
-.007,-.011,
-.007695,-.010939,
-.008368,-.010759,
-.009,-.010464,
-.009571,-.010064,
-.010064,-.009571,
-.010464,-.009,
-.010759,-.008368,
-.010939,-.007695,
-.011,-.007,
-.011,.007,
-.010939,.007695,
-.010759,.008368,
-.010464,.009,
-.010064,.009571,
-.009571,.010064,
-.009,.010464,
-.008368,.010759,
-.007695,.010939,
-.007,.011,
0.0*
%
%ADD60MACRO60*%
%AMMACRO37*
4,1,40,.008,-.012,
-.008,-.012,
-.008695,-.011939,
-.009368,-.011759,
-.01,-.011464,
-.010571,-.011064,
-.011064,-.010571,
-.011464,-.01,
-.011759,-.009368,
-.011939,-.008695,
-.012,-.008,
-.012,.008,
-.011939,.008695,
-.011759,.009368,
-.011464,.01,
-.011064,.010571,
-.010571,.011064,
-.01,.011464,
-.009368,.011759,
-.008695,.011939,
-.008,.012,
.008,.012,
.008695,.011939,
.009368,.011759,
.01,.011464,
.010571,.011064,
.011064,.010571,
.011464,.01,
.011759,.009368,
.011939,.008695,
.012,.008,
.012,-.008,
.011939,-.008695,
.011759,-.009368,
.011464,-.01,
.011064,-.010571,
.010571,-.011064,
.01,-.011464,
.009368,-.011759,
.008695,-.011939,
.008,-.012,
0.0*
%
%ADD37MACRO37*%
%AMMACRO31*
4,1,40,.012,.008,
.012,-.008,
.011939,-.008695,
.011759,-.009368,
.011464,-.01,
.011064,-.010571,
.010571,-.011064,
.01,-.011464,
.009368,-.011759,
.008695,-.011939,
.008,-.012,
-.008,-.012,
-.008695,-.011939,
-.009368,-.011759,
-.01,-.011464,
-.010571,-.011064,
-.011064,-.010571,
-.011464,-.01,
-.011759,-.009368,
-.011939,-.008695,
-.012,-.008,
-.012,.008,
-.011939,.008695,
-.011759,.009368,
-.011464,.01,
-.011064,.010571,
-.010571,.011064,
-.01,.011464,
-.009368,.011759,
-.008695,.011939,
-.008,.012,
.008,.012,
.008695,.011939,
.009368,.011759,
.01,.011464,
.010571,.011064,
.011064,.010571,
.011464,.01,
.011759,.009368,
.011939,.008695,
.012,.008,
0.0*
%
%ADD31MACRO31*%
%ADD82C,.012*%
%ADD83C,.013*%
%ADD84C,.014*%
%ADD85C,.015*%
%ADD86C,.016*%
%ADD87C,.006*%
%ADD88C,.005*%
%ADD89C,.0035*%
%ADD90C,.0049*%
%ADD91C,.00375*%
%ADD92C,.00575*%
%ADD99R,.02X.008*%
%ADD103R,.008X.016*%
%ADD101C,.03004*%
%ADD102R,.008X.017*%
%ADD98R,.017X.008*%
%ADD97R,.0171X.008*%
%ADD96R,.008X.019*%
%ADD94R,.019X.008*%
%ADD104C,.04404*%
%ADD95C,.02804*%
%ADD100R,.008X.01885*%
%ADD93R,.008X.008*%
G75*
%LPD*%
G75*
G36*
G01X443151Y493059D02*
X476035Y498319D01*
G03X495140Y520723I-3584J22404D01*
G01Y562992D01*
G02X500010Y567862I4870J0D01*
G01X818898D01*
G02X823768Y562992I0J-4870D01*
G01Y7874D01*
G02X818898Y3004I-4870J0D01*
G01X168082D01*
Y8000D01*
X344155D01*
G03X347185I1515J2237D01*
G01X358328D01*
G03X361358I1515J2237D01*
G01X372501D01*
G03X375531I1515J2237D01*
G01X386674D01*
G03X389704I1515J2237D01*
G01X400848D01*
G03X403878I1515J2237D01*
G01X415021D01*
G03X418051I1515J2237D01*
G01X429194D01*
G03X432224I1515J2237D01*
G01X443367D01*
G03X446397I1515J2237D01*
G01X457540D01*
G03X460570I1515J2237D01*
G01X471714D01*
G03X474744I1515J2237D01*
G01X485887D01*
G03X488917I1515J2237D01*
G01X500060D01*
G03X503090I1515J2237D01*
G01X514233D01*
G03X517263I1515J2237D01*
G01X528407D01*
G03X531437I1515J2237D01*
G01X542580D01*
G03X545610I1515J2237D01*
G01X556753D01*
G03X559783I1515J2237D01*
G01X570926D01*
G03X573956I1515J2237D01*
G01X585099D01*
G03X588129I1515J2237D01*
G01X714233D01*
G03X717263I1515J2237D01*
G01X728406D01*
G03X731436I1515J2237D01*
G01X742579D01*
G03X745609I1515J2237D01*
G01X756752D01*
G03X759782I1515J2237D01*
G01X818772D01*
Y562866D01*
X500136D01*
Y520723D01*
G02X476824Y493386I-27685J1D01*
G01X443548Y488063D01*
X383223D01*
X349967Y493383D01*
G02X326656Y520719I4374J27337D01*
G01Y563116D01*
X7896D01*
X7750Y562970D01*
Y562762D01*
X7896Y562616D01*
X8000D01*
Y8000D01*
X102995D01*
Y3004D01*
X7874D01*
G02X3004Y7874I0J4870D01*
G01Y562992D01*
G02X7874Y567862I4870J0D01*
G01X326783D01*
G02X331650Y563117I-1J-4870D01*
G01Y562616D01*
X331652D01*
Y520719D01*
G03X350756Y498316I22689J1D01*
G01X383620Y493059D01*
X443151D01*
G37*
G36*
G01X48630Y203601D02*
X48065Y204166D01*
Y205435D01*
X47000Y206500D01*
X46365D01*
G03X46300Y206502I-82J-1599D01*
G01X43700D01*
G03X43683Y206501I85J-1597D01*
G01X43599D01*
X43000Y207100D01*
Y211170D01*
X48617Y216787D01*
X60564D01*
X61578Y215773D01*
Y204453D01*
X60726Y203601D01*
X48630D01*
G37*
G36*
G01X203002Y159377D02*
X191468D01*
X190300Y160545D01*
Y211200D01*
X190950Y211850D01*
X202450D01*
X204000Y210300D01*
Y160375D01*
X203002Y159377D01*
G37*
G36*
G01X184650Y124400D02*
X173800D01*
X173350Y124850D01*
Y136152D01*
X175632Y138434D01*
X185515D01*
X186039Y137910D01*
Y134400D01*
X185900Y134261D01*
Y125650D01*
X184650Y124400D01*
G37*
G36*
G01X153196Y412604D02*
X152250Y413550D01*
Y417296D01*
X152251Y417306D01*
G03X152260Y417470I-1593J170D01*
G01Y419070D01*
G03X152251Y419234I-1602J-6D01*
G01X152250Y419244D01*
Y435250D01*
X153450Y436450D01*
X155404D01*
X157558Y438604D01*
Y456104D01*
X154058Y459604D01*
Y470604D01*
X154558Y471104D01*
X169058D01*
X169558Y470604D01*
Y458604D01*
X166050Y455096D01*
Y436400D01*
X167857Y434593D01*
Y413557D01*
X166923Y412623D01*
X164077D01*
X164058Y412604D01*
X153196D01*
G37*
G36*
G01X177493Y413209D02*
X170663D01*
X169067Y414805D01*
Y436252D01*
X167663Y437656D01*
Y448827D01*
X168365Y449529D01*
X176344D01*
X178897Y446976D01*
Y414613D01*
X177493Y413209D01*
G37*
G36*
G01X142130Y414510D02*
X139570Y417070D01*
Y446522D01*
X141388Y448340D01*
X155640D01*
X156140Y447840D01*
Y438885D01*
X155225Y437970D01*
X153168D01*
X151150Y435952D01*
Y435849D01*
X151048Y435748D01*
Y416119D01*
X149440Y414510D01*
X142130D01*
G37*
G36*
G01X238487Y128200D02*
X224900D01*
X221000Y132100D01*
Y159900D01*
X221800Y160700D01*
X241000D01*
X242912Y158788D01*
Y132625D01*
X238487Y128200D01*
G37*
G36*
G01X274433Y129479D02*
X252159D01*
X245201Y136437D01*
Y249330D01*
X248149Y252278D01*
X275445D01*
X277000Y250723D01*
Y132046D01*
X274433Y129479D01*
G37*
G36*
G01X241600Y200400D02*
X222350D01*
X219150Y203600D01*
Y245697D01*
X222049Y248596D01*
X241801D01*
X244000Y246397D01*
Y202800D01*
X241600Y200400D01*
G37*
G36*
G01X262900Y389200D02*
X236650D01*
X236250Y389600D01*
Y401450D01*
X236800Y402000D01*
X263250D01*
X263800Y401450D01*
Y390100D01*
X262900Y389200D01*
G37*
G36*
G01X225500Y406500D02*
X225000Y407000D01*
Y419406D01*
X226196Y420602D01*
X250960D01*
X252500Y419062D01*
Y416362D01*
X252489Y416330D01*
G03X252398Y415800I1511J-532D01*
G01Y414200D01*
G03X252489Y413670I1602J2D01*
G01X252500Y413638D01*
Y408000D01*
X251000Y406500D01*
X225500D01*
G37*
G36*
G01X282000Y138500D02*
X279500D01*
X278500Y139500D01*
Y247500D01*
X279000Y248000D01*
X282000D01*
X286500Y243500D01*
X319030D01*
X322420Y240110D01*
Y166120D01*
X303500Y147200D01*
Y143000D01*
X302500Y142000D01*
X285500D01*
X282000Y138500D01*
G37*
G36*
G01X279100Y115100D02*
X278600Y115600D01*
Y126500D01*
X284500Y132400D01*
Y139000D01*
X286000Y140500D01*
X302073D01*
X302500Y140073D01*
Y130500D01*
X302486Y130486D01*
Y129687D01*
X287899Y115100D01*
X279100D01*
G37*
G36*
G01X326450Y272750D02*
X316600D01*
X316275Y273075D01*
Y275925D01*
X316900Y276550D01*
X326700D01*
X327025Y276225D01*
Y273325D01*
X326450Y272750D01*
G37*
G36*
G01X287500Y245000D02*
X284500Y248000D01*
Y257500D01*
X285000Y258000D01*
X297544D01*
X303000Y252544D01*
Y245500D01*
X302500Y245000D01*
X287500D01*
G37*
G36*
G01X309500Y277700D02*
X302100Y285100D01*
Y290119D01*
X302430Y290448D01*
X308134D01*
X310882Y287700D01*
X311635D01*
G03X311700Y287698I82J1599D01*
G01X313300D01*
G03X313365Y287700I-17J1601D01*
G01X314100D01*
X314900Y288500D01*
Y289235D01*
G03X314902Y289300I-1599J82D01*
G01Y290802D01*
X315400Y291300D01*
X324600D01*
X325667Y290233D01*
X325666Y290149D01*
G03X326350Y288530I2202J-24D01*
G01Y277970D01*
G02X326143Y277771I-200J1D01*
G03X326087Y277772I-57J-1601D01*
G01X324487D01*
G03X324249Y277754I1J-1602D01*
G01X324234Y277752D01*
X322840D01*
X322825Y277754D01*
G03X322587Y277772I-239J-1584D01*
G01X320987D01*
G03X320749Y277754I1J-1602D01*
G01X320734Y277752D01*
X316402D01*
X316351Y277700D01*
X309500D01*
G37*
G36*
G01X361635Y295017D02*
X360840Y295812D01*
Y306945D01*
X361622Y307727D01*
X368650D01*
X371580Y304797D01*
X377575D01*
X378900Y303472D01*
Y296350D01*
X377567Y295017D01*
X371174D01*
X371158Y295020D01*
G03X370889Y295042I-265J-1579D01*
G01X368889D01*
G03X368620Y295020I-4J-1601D01*
G01X368604Y295017D01*
X361635D01*
G37*
G36*
G01X375268Y266942D02*
X361826D01*
X361031Y267737D01*
Y278870D01*
X361813Y279652D01*
X375350D01*
X376526Y278476D01*
Y268200D01*
X375268Y266942D01*
G37*
G36*
G01X377300Y243800D02*
X362233D01*
X360683Y245350D01*
Y250404D01*
X361033Y250754D01*
X361514Y251234D01*
X376771D01*
X378200Y249805D01*
Y244700D01*
X377300Y243800D01*
G37*
G36*
G01X345400Y298900D02*
X346821Y300321D01*
X346883Y300331D01*
G03X348400Y303613I-383J2169D01*
G01Y307156D01*
X348900Y307656D01*
X359365D01*
X359621Y307400D01*
Y295481D01*
X359143Y295003D01*
X349003D01*
X348100Y294100D01*
Y290785D01*
X347520Y290205D01*
X346042D01*
X345250Y290997D01*
Y292650D01*
X345400Y292800D01*
Y298900D01*
G37*
G36*
G01X359050Y251542D02*
X359307Y251285D01*
Y246292D01*
X357354Y244339D01*
X345241D01*
X344198Y245382D01*
Y256610D01*
G03Y256790I-2200J90D01*
G01Y263302D01*
X340900Y266600D01*
Y276408D01*
X340911Y276440D01*
G03X341002Y276970I-1511J532D01*
G01Y278570D01*
G03X340911Y279100I-1602J-2D01*
G01X340900Y279132D01*
Y284438D01*
X340911Y284470D01*
G03X341002Y285000I-1511J532D01*
G01Y286600D01*
G03X340911Y287130I-1602J-2D01*
G01X340900Y287162D01*
Y290400D01*
X341200Y290700D01*
X343800D01*
X344000Y290500D01*
Y283800D01*
X345200Y282600D01*
X347800D01*
X348276Y282124D01*
Y280036D01*
X348332D01*
X348786Y279581D01*
X359493D01*
X359749Y279325D01*
Y267819D01*
X359490Y267560D01*
X359451D01*
G03X358869Y267670I-583J-1492D01*
G01X357469D01*
G03X356919Y267572I2J-1602D01*
G01X356886Y267560D01*
X349577D01*
X348032Y266015D01*
Y251968D01*
X348451Y251549D01*
X357454D01*
X357462Y251548D01*
G03X357598Y251542I139J1596D01*
G01X359050D01*
G37*
G36*
G01X491113Y241127D02*
X490098Y240113D01*
Y240098D01*
X490013Y240013D01*
Y226900D01*
X489787Y226674D01*
X420214D01*
X420074Y226814D01*
Y228079D01*
X421609Y229614D01*
X424415D01*
X424876Y230075D01*
Y234533D01*
X424268Y235141D01*
Y236508D01*
X424886Y237126D01*
X478376D01*
X478944Y236558D01*
X482371D01*
X482600Y236787D01*
Y283000D01*
X483000Y283400D01*
Y285904D01*
X483096Y286000D01*
X488800D01*
X490600Y287800D01*
Y289239D01*
G03X490602Y289300I-1399J76D01*
G01Y289702D01*
X490800Y289900D01*
X492820D01*
X493272Y290352D01*
X494653D01*
X494990Y290015D01*
Y288548D01*
X494600Y288158D01*
Y242600D01*
X493700Y241700D01*
X491700D01*
X491458Y241458D01*
X491444D01*
X491157Y241171D01*
X491156Y241170D01*
G03X491114Y241128I970J-1012D01*
G01X491113Y241127D01*
G37*
G36*
G01X419182Y226909D02*
X420191Y225900D01*
X490304D01*
X490600Y226196D01*
Y239905D01*
X491652Y240957D01*
X492802D01*
X492966Y240793D01*
Y223302D01*
X492182Y222518D01*
X401840D01*
X400878Y223480D01*
Y226037D01*
X400910Y226069D01*
Y226752D01*
X401144Y226987D01*
X403802D01*
X404589Y226200D01*
X408568D01*
X409734Y227366D01*
Y229585D01*
X410286Y230137D01*
X414631D01*
X419312Y234818D01*
X423742D01*
X424334Y234226D01*
Y230528D01*
X424242Y230436D01*
X421085D01*
X419182Y228533D01*
Y226909D01*
G37*
G36*
G01X481800Y237601D02*
X481683Y237484D01*
X478968D01*
X478114Y238338D01*
X427495D01*
X426991Y238842D01*
Y240366D01*
X427135Y240510D01*
X428685D01*
X429068Y240893D01*
Y241868D01*
X429181Y241981D01*
X477452D01*
X478614Y243143D01*
Y280757D01*
X477846Y281525D01*
X474571D01*
X474028Y280982D01*
Y247792D01*
X473368Y247132D01*
X432364D01*
X431287Y248209D01*
Y264342D01*
X431695Y264750D01*
X433995D01*
X434450Y264295D01*
Y251450D01*
X435250Y250650D01*
X438340D01*
X441140Y253450D01*
X469168D01*
X470100Y254382D01*
Y257400D01*
X469259Y258241D01*
X440687D01*
X440028Y258900D01*
Y260328D01*
X440550Y260850D01*
X469550D01*
X469841Y261141D01*
Y265221D01*
X469482Y265580D01*
X441729D01*
X440045Y267264D01*
Y268156D01*
X441826Y269937D01*
X465639D01*
X465810Y270108D01*
X468846D01*
X470700Y271962D01*
Y276800D01*
X470219Y277281D01*
X470200D01*
X470015Y277466D01*
X436260D01*
X433813Y275019D01*
Y272924D01*
X431628Y270739D01*
X428761D01*
X428200Y271300D01*
Y272200D01*
X430900Y274900D01*
Y276300D01*
X424600Y282600D01*
X417006D01*
X416479Y283127D01*
Y285079D01*
X416808Y285408D01*
X424892D01*
X427200Y283100D01*
X430888D01*
X432388Y281600D01*
X433800D01*
X434900Y282700D01*
X438700D01*
X439800Y281600D01*
X441600D01*
X442700Y282700D01*
X447000D01*
X448100Y281600D01*
X449433D01*
X450432Y282600D01*
X458500D01*
X459500Y281600D01*
X461294D01*
X462400Y282706D01*
X466306D01*
X467412Y281600D01*
X468900D01*
X470383Y283083D01*
X471217D01*
X472259Y284125D01*
X477126D01*
X477151Y284100D01*
X479084D01*
X480906Y285922D01*
X481978D01*
X482200Y285700D01*
Y283800D01*
X481800Y283400D01*
Y237601D01*
G37*
G36*
G01X437850Y251587D02*
X435832D01*
X435267Y252152D01*
Y264587D01*
X433999Y265855D01*
X431687D01*
X431402Y266140D01*
Y268915D01*
X434600Y272113D01*
Y274491D01*
X436837Y276728D01*
X465517D01*
X465678Y276889D01*
X469503D01*
X469709Y276683D01*
Y271757D01*
X468693Y270741D01*
X464331D01*
X464329Y270743D01*
X441417D01*
X439017Y268344D01*
Y266428D01*
X440558Y264888D01*
X440660Y264786D01*
X468626D01*
X469049Y264363D01*
Y262300D01*
X468549Y261800D01*
X463744D01*
X463600Y261656D01*
X440145D01*
X439237Y260748D01*
Y258457D01*
X440238Y257456D01*
X468697D01*
X469140Y257013D01*
Y254950D01*
X468462Y254272D01*
X440535D01*
X437850Y251587D01*
G37*
G36*
G01X429220Y288804D02*
X428996Y289028D01*
G02X429279Y289711I283J283D01*
G01X448109D01*
G02X448391Y289028I0J-400D01*
G01X447793Y288429D01*
G03X449845Y286377I1026J-1026D01*
G01X450723Y287254D01*
G02X451394Y287067I283J-283D01*
G03X454140Y287623I1362J335D01*
G01X454123Y287723D01*
X455100Y288700D01*
X458200D01*
X458519Y288381D01*
X458509Y288371D01*
Y286543D01*
X459784Y285268D01*
X465860D01*
X466777Y286185D01*
Y287893D01*
X467538Y288654D01*
X470546D01*
X471130Y288070D01*
Y287897D01*
X471119Y287865D01*
G03Y286939I1323J-463D01*
G01X471130Y286907D01*
Y284730D01*
X471100Y284700D01*
Y283875D01*
X471092Y283848D01*
G03X471073Y283773I1349J-382D01*
G01X471000Y283700D01*
X469600D01*
X469400Y283500D01*
Y283146D01*
X468700Y282446D01*
X468009D01*
X466928Y283528D01*
X462058D01*
X460976Y282446D01*
X460254D01*
X460250Y282450D01*
X459850D01*
X458900Y283400D01*
X450031D01*
X449077Y282446D01*
X448540D01*
X447486Y283500D01*
X442400D01*
X441345Y282446D01*
X440454D01*
X439376Y283524D01*
X434525D01*
X433500Y282500D01*
X432725D01*
X431325Y283900D01*
X427532D01*
X425232Y286200D01*
X416800D01*
X416352Y286648D01*
Y289394D01*
X416669Y289711D01*
X426114D01*
Y288935D01*
X427733Y287317D01*
X427741Y287247D01*
G03X429290Y288796I1393J156D01*
G01X429220Y288804D01*
G37*
G36*
G01X476867Y242671D02*
X429010D01*
X427681Y244000D01*
X424699D01*
X424454Y244245D01*
Y246561D01*
X424821Y246928D01*
X427253D01*
X428268Y245913D01*
X473068D01*
X474633Y247478D01*
Y280104D01*
X475187Y280658D01*
X477214D01*
X477741Y280131D01*
Y243545D01*
X476867Y242671D01*
G37*
G36*
G01X451700Y343307D02*
X449900D01*
X449800Y343407D01*
Y346469D01*
X446200Y350069D01*
X439818D01*
X439143Y350744D01*
Y356643D01*
X439800Y357300D01*
X451384D01*
X451900Y356784D01*
Y343507D01*
X451700Y343307D01*
G37*
G36*
G01X504078Y233861D02*
X506648Y236432D01*
X508522D01*
X508865Y236089D01*
Y211615D01*
X508606Y211356D01*
X505394D01*
X505300Y211450D01*
Y212272D01*
X505305Y212294D01*
G03Y212904I-1368J305D01*
G01X505300Y212926D01*
Y213500D01*
X504121Y214679D01*
X504113Y214747D01*
G03X503140Y215914I-1391J-171D01*
G01X503000Y215957D01*
Y217119D01*
X503140Y217162D01*
G03X504101Y218251I-418J1338D01*
G01X504112Y218312D01*
X505400Y219600D01*
Y221150D01*
X504125Y222425D01*
X504123Y222503D01*
G03X503140Y223788I-1401J-53D01*
G01X503000Y223831D01*
Y224969D01*
X503140Y225012D01*
G03X504123Y226342I-418J1338D01*
G01X504124Y226424D01*
X505350Y227650D01*
Y229250D01*
X504111Y230489D01*
X504099Y230550D01*
G03X503140Y231629I-1377J-259D01*
G01X503000Y231672D01*
Y232838D01*
X503140Y232881D01*
G03X504063Y233813I-419J1338D01*
G01X504078Y233861D01*
G37*
G36*
G01X499400Y203300D02*
X499050Y203650D01*
Y205450D01*
X499450Y205850D01*
X503950D01*
X505300Y207200D01*
Y208294D01*
X505306Y208318D01*
G03X505338Y208494I-1370J340D01*
G01X505348Y208578D01*
Y208672D01*
G03X505306Y209006I-1411J-8D01*
G01X505300Y209030D01*
Y210450D01*
X505400Y210550D01*
X508599D01*
X509978Y211929D01*
Y235822D01*
X510158Y236002D01*
X512131D01*
X512330Y235803D01*
Y233964D01*
X512324Y233957D01*
Y233746D01*
X512315Y233717D01*
G03X512254Y233300I1385J-416D01*
G01Y224201D01*
X516154Y220300D01*
X517200Y218645D01*
Y208263D01*
X512337Y203400D01*
X509500D01*
X509400Y203300D01*
X499400D01*
G37*
G36*
G01X495650Y348350D02*
X496900Y349600D01*
X496970Y349608D01*
G03X497443Y349733I-168J1593D01*
G01X497481Y349750D01*
X498900D01*
X499400Y349250D01*
Y346900D01*
X499950Y346350D01*
X501662D01*
X501682Y346346D01*
G03X502594I456J2154D01*
G01X502614Y346350D01*
X505786D01*
X505806Y346346D01*
G03X506718I456J2154D01*
G01X506738Y346350D01*
X509662D01*
X509682Y346346D01*
G03X510594I456J2154D01*
G01X510614Y346350D01*
X511400D01*
X512400Y347350D01*
Y353050D01*
X511550Y353900D01*
X510765D01*
G03X510700Y353902I-82J-1599D01*
G01X509300D01*
G03X509235Y353900I17J-1601D01*
G01X506765D01*
G03X506700Y353902I-82J-1599D01*
G01X505300D01*
G03X505235Y353900I17J-1601D01*
G01X505100D01*
X504750Y354250D01*
Y359250D01*
X506494Y360994D01*
X513906D01*
X515550Y359350D01*
Y354450D01*
X516600Y353400D01*
X517735D01*
G03X517800Y353398I82J1599D01*
G01X519200D01*
G03X519265Y353400I-17J1601D01*
G01X521735D01*
G03X521800Y353398I82J1599D01*
G01X523200D01*
G03X523265Y353400I-17J1601D01*
G01X529950D01*
X531050Y352300D01*
Y344500D01*
X530700Y344150D01*
X496250D01*
X495650Y344750D01*
Y348350D01*
G37*
G36*
G01X455000Y343100D02*
X454900Y343200D01*
Y348100D01*
X456586Y349786D01*
Y355233D01*
X456592Y355257D01*
G03X456642Y355655I-1551J397D01*
G01Y357055D01*
G03X456592Y357453I-1601J1D01*
G01X456586Y357477D01*
Y359659D01*
X457427Y360500D01*
X463500D01*
X465000Y359000D01*
Y358163D01*
X464992Y358135D01*
G03Y356865I2108J-635D01*
G01X465000Y356837D01*
Y356400D01*
X465900Y355500D01*
X466178D01*
X466216Y355483D01*
G03X467984I884J2017D01*
G01X468022Y355500D01*
X468700D01*
X469100Y355100D01*
Y353500D01*
X468701Y353101D01*
X468617D01*
G03X468600Y353102I-102J-1596D01*
G01X467200D01*
G03X467135Y353100I17J-1601D01*
G01X466500D01*
X464200Y350800D01*
Y350790D01*
X459912Y346502D01*
X459300D01*
G03X459235Y346500I17J-1601D01*
G01X458300D01*
X457500Y345700D01*
Y343300D01*
X457300Y343100D01*
X456665D01*
G03X456600Y343102I-82J-1599D01*
G01X455200D01*
G03X455135Y343100I17J-1601D01*
G01X455000D01*
G37*
G36*
G01X504063Y439148D02*
X503300Y439911D01*
Y476400D01*
X504900Y478000D01*
X517000D01*
X517800Y477200D01*
Y457665D01*
G03X517798Y457600I1599J-82D01*
G01Y456000D01*
G03X517800Y455935I1601J17D01*
G01Y441653D01*
X515295Y439148D01*
X504063D01*
G37*
G36*
G01X519100Y455100D02*
Y477500D01*
X519700Y478100D01*
X525000D01*
X525300Y477800D01*
Y474450D01*
X526050Y473700D01*
X526885D01*
G03X526950Y473698I82J1599D01*
G01X528350D01*
G03X528415Y473700I-17J1601D01*
G01X543569D01*
X544600Y472669D01*
Y456700D01*
X543000Y455100D01*
X519100D01*
G37*
G36*
G01X553900Y434400D02*
X530650D01*
X529550Y435500D01*
Y451150D01*
X530700Y452300D01*
X553200D01*
X555100Y450400D01*
Y435600D01*
X553900Y434400D01*
G37*
G36*
G01X636543Y33895D02*
X633234Y37204D01*
Y45193D01*
X642241Y54200D01*
X657800D01*
X657850Y54150D01*
X659997D01*
X661950Y52197D01*
Y50050D01*
X661001Y49101D01*
X660588D01*
G03X660550Y49102I-61J-1600D01*
G01X659150D01*
G03X659112Y49101I23J-1601D01*
G01X657919D01*
X657774Y49246D01*
X654457D01*
X653595Y48384D01*
Y46846D01*
X653450Y46702D01*
X642437D01*
X642436Y46700D01*
X642303D01*
X637941Y42338D01*
Y41927D01*
X637926Y41890D01*
G03Y40048I2218J-921D01*
G01X637941Y40011D01*
Y40009D01*
X637943Y40007D01*
X637958Y39974D01*
G03X639149Y38783I2186J995D01*
G01X639182Y38768D01*
X640000Y37950D01*
X642350D01*
X642451Y37848D01*
X646752D01*
X646800Y37800D01*
X654000D01*
X654200Y37600D01*
Y35550D01*
X653800Y35150D01*
X648125D01*
X646870Y33895D01*
X636543D01*
G37*
G36*
G01X620400Y100200D02*
X619700Y100900D01*
Y105700D01*
X620398Y106398D01*
X634602D01*
X635600Y105400D01*
Y100600D01*
X635200Y100200D01*
X620400D01*
G37*
G36*
G01Y107600D02*
X619400Y108600D01*
Y129600D01*
X620800Y131000D01*
X633900D01*
X635000Y132100D01*
Y149500D01*
X639400Y153900D01*
X641800D01*
X642300Y153400D01*
Y143600D01*
X642500Y143400D01*
Y108800D01*
X641300Y107600D01*
X632265D01*
G03X632200Y107602I-82J-1599D01*
G01X630800D01*
G03X630735Y107600I17J-1601D01*
G01X620400D01*
G37*
G36*
G01X617200Y132500D02*
X616500Y133200D01*
Y137000D01*
X618900Y139400D01*
X632300D01*
X633500Y138200D01*
Y133000D01*
X633000Y132500D01*
X617200D01*
G37*
G36*
G01X598257Y230237D02*
X597700Y230794D01*
Y253600D01*
X598600Y254500D01*
X605500D01*
X606277Y253723D01*
Y240059D01*
X606271Y240036D01*
G03X606224Y239652I1555J-385D01*
G01Y237652D01*
G03X606271Y237268I1602J1D01*
G01X606277Y237245D01*
Y236435D01*
X606260Y236397D01*
G03X606124Y235752I1466J-646D01*
G01Y234152D01*
G03X606260Y233507I1602J1D01*
G01X606277Y233469D01*
Y231477D01*
X605037Y230237D01*
X598257D01*
G37*
G36*
G01X622500Y233000D02*
X621650Y233850D01*
Y253650D01*
X622500Y254500D01*
X640500D01*
X641898Y253102D01*
Y250700D01*
G03X641900Y250635I1601J17D01*
G01Y239762D01*
X641889Y239730D01*
G03X641798Y239200I1511J-532D01*
G01Y237600D01*
G03X641889Y237070I1602J2D01*
G01X641900Y237038D01*
Y235765D01*
G03X641898Y235700I1599J-82D01*
G01Y233700D01*
G03X641900Y233631I1602J12D01*
G01Y233550D01*
X641350Y233000D01*
X622500D01*
G37*
G36*
G01X646346Y214154D02*
X651900Y208600D01*
X656089D01*
X656090Y208598D01*
X660902D01*
X661500Y208000D01*
Y206000D01*
X661101Y205601D01*
X622899D01*
X622500Y206000D01*
Y212322D01*
X624332Y214154D01*
X646346D01*
G37*
G36*
G01X619874Y230700D02*
X616072D01*
X615500Y231272D01*
Y262000D01*
X616150Y262650D01*
X626850D01*
X627500Y262000D01*
Y256500D01*
X627000Y256000D01*
X621500D01*
X620400Y254900D01*
Y231226D01*
X619874Y230700D01*
G37*
G36*
G01X608001Y230426D02*
X607463Y230964D01*
X607478Y230979D01*
Y254221D01*
X607390Y254309D01*
Y254610D01*
X606000Y256000D01*
X603000D01*
X602000Y257000D01*
Y261500D01*
X603150Y262650D01*
X613350D01*
X614000Y262000D01*
Y230866D01*
X613560Y230426D01*
X608001D01*
G37*
G36*
G01X595800Y263500D02*
X592365Y266935D01*
Y280110D01*
X593215Y280960D01*
X622514D01*
X630486Y272988D01*
X662239D01*
X662934Y272294D01*
Y264742D01*
X661692Y263500D01*
X660699D01*
X660698Y263502D01*
X650052D01*
X650051Y263500D01*
X647949D01*
X647948Y263502D01*
X636802D01*
X636801Y263500D01*
X627699D01*
X627348Y263852D01*
X618801D01*
G03X618726Y263854I-80J-1600D01*
G01X617326D01*
G03X617251Y263852I5J-1602D01*
G01X615652D01*
X615301Y263500D01*
X614199D01*
X613848Y263852D01*
X612301D01*
G03X612226Y263854I-80J-1600D01*
G01X610826D01*
G03X610751Y263852I5J-1602D01*
G01X602652D01*
X602301Y263500D01*
X595800D01*
G37*
G36*
G01X630295Y426600D02*
X602100D01*
X598300Y430400D01*
Y467900D01*
X598450Y468050D01*
X609900D01*
X610550Y467400D01*
Y437400D01*
X611450Y436500D01*
X629921D01*
X630824Y435597D01*
Y427129D01*
X630295Y426600D01*
G37*
G36*
G01X624300Y457800D02*
X623900Y458200D01*
Y466400D01*
X624300Y466800D01*
X630244D01*
X631400Y465644D01*
Y458300D01*
X630900Y457800D01*
X624300D01*
G37*
G36*
G01X631100Y438300D02*
X615400D01*
X614800Y438900D01*
Y447800D01*
X615500Y448500D01*
X630200D01*
X631600Y447100D01*
Y438800D01*
X631100Y438300D01*
G37*
G36*
G01X642949Y39050D02*
X642476Y39523D01*
Y40393D01*
X642481Y40416D01*
G03Y41522I-2337J553D01*
G01X642476Y41545D01*
Y45041D01*
X642935Y45500D01*
X644304D01*
X644312Y45499D01*
G03X644448Y45494I127J1596D01*
G01X646048D01*
G03X646184Y45499I9J1601D01*
G01X646192Y45500D01*
X647804D01*
X647812Y45499D01*
G03X647948Y45494I127J1596D01*
G01X649548D01*
G03X649684Y45499I9J1601D01*
G01X649692Y45500D01*
X651304D01*
X651312Y45499D01*
G03X651448Y45494I127J1596D01*
G01X653048D01*
G03X653184Y45499I9J1601D01*
G01X653192Y45500D01*
X653381D01*
X654488Y44393D01*
X655186D01*
G03X655251Y44392I57J1600D01*
G01X656851D01*
G03X656916Y44393I8J1601D01*
G01X657034D01*
X657300Y44127D01*
Y40181D01*
X656169Y39050D01*
X646154D01*
X646130Y39056D01*
G03X645750Y39102I-381J-1556D01*
G01X644150D01*
G03X643770Y39056I1J-1602D01*
G01X643746Y39050D01*
X642949D01*
G37*
G36*
G01X660748Y30349D02*
X657551Y27152D01*
X655698D01*
X655400Y27450D01*
Y32098D01*
X660748D01*
Y30349D01*
G37*
G36*
G01X650737Y18850D02*
X650187Y19400D01*
Y23600D01*
X650487Y23900D01*
X656000D01*
X656348Y24248D01*
X658753D01*
X659155Y24650D01*
X660944D01*
G02X661344Y24243I0J-400D01*
G01Y22614D01*
G03X661394Y22216I1601J-1D01*
G01X661400Y22192D01*
Y19500D01*
X660750Y18850D01*
X650737D01*
G37*
G36*
G01X643859Y108256D02*
X643050Y109065D01*
Y122550D01*
X643500Y123000D01*
Y150100D01*
X644100Y150700D01*
X645900D01*
X647099Y151899D01*
X647216Y151860D01*
G03X649663Y152300I819J2470D01*
G01X652100D01*
X652500Y151900D01*
Y146950D01*
X652250Y146700D01*
X650300D01*
X649400Y145800D01*
Y142003D01*
X649398Y141989D01*
G03Y141475I1783J-257D01*
G01X649400Y141461D01*
Y122600D01*
X648150Y121350D01*
Y114147D01*
X649950Y112347D01*
Y108450D01*
X649756Y108256D01*
X643859D01*
G37*
G36*
G01X689062Y193215D02*
X690694Y191583D01*
Y188956D01*
X691400Y188250D01*
X692800D01*
X693838Y189288D01*
Y195551D01*
X694545Y196258D01*
X697310D01*
X697869Y195699D01*
Y194155D01*
X697948Y194076D01*
X697955Y194005D01*
G03X698762Y193198I897J90D01*
G01X698833Y193191D01*
X700082Y191942D01*
X700092Y191879D01*
G03X700136Y191693I1481J252D01*
G01X700144Y191665D01*
Y188956D01*
X700700Y188400D01*
X702550D01*
X703423Y189273D01*
Y192920D01*
X702254Y194089D01*
Y196270D01*
X702584Y196600D01*
X705074D01*
X705508Y196166D01*
Y194051D01*
X705950Y193609D01*
Y188950D01*
X706600Y188300D01*
X708450D01*
X709450Y189300D01*
Y196261D01*
X709881Y196692D01*
X712248D01*
X712635Y196305D01*
Y193235D01*
X712300Y192900D01*
Y191385D01*
X713652Y190033D01*
Y187601D01*
X713993Y187260D01*
X717612D01*
X718241Y187889D01*
Y190606D01*
X717089Y191758D01*
Y196327D01*
X717362Y196600D01*
X719840D01*
X720183Y196257D01*
Y193517D01*
X720900Y192800D01*
Y191800D01*
X720600Y191500D01*
Y187900D01*
X721500Y187000D01*
Y185800D01*
X720600Y184900D01*
Y181500D01*
X721500Y180600D01*
Y179400D01*
X720600Y178500D01*
Y175800D01*
X721500Y174900D01*
Y173089D01*
X720740Y172330D01*
Y172290D01*
X720700Y172250D01*
Y169351D01*
X721551Y168500D01*
Y160541D01*
X720840Y159831D01*
Y157715D01*
G03X721551Y156496I1402J1D01*
G01Y154242D01*
X720740Y153432D01*
Y151175D01*
G03X721551Y149904I1401J0D01*
G01Y147943D01*
X720740Y147133D01*
Y147090D01*
X720700Y147049D01*
Y144252D01*
X721576Y143376D01*
X721700Y143251D01*
Y139049D01*
X721552Y138902D01*
X720148D01*
X719850Y139200D01*
Y140000D01*
X719250Y140600D01*
X716250D01*
X715750Y141100D01*
Y142950D01*
X715350Y143350D01*
X713050D01*
X712450Y142750D01*
Y140950D01*
X711295Y139795D01*
G02X710746Y139779I-283J283D01*
G03X710147Y140008I-600J-672D01*
G01X708747D01*
G03X707846Y139106I0J-901D01*
G01Y138446D01*
X707200Y137800D01*
Y137596D01*
X706810Y137206D01*
Y136310D01*
G03X705649Y135300I1051J-2380D01*
G01X700800D01*
X700485Y134985D01*
X700385Y135000D01*
G03X698426Y134500I-387J-2573D01*
G01X695055D01*
G03X692723Y134717I-1381J-2205D01*
G01X692687Y134703D01*
X673014D01*
X672200Y133889D01*
Y131912D01*
X671488Y131200D01*
X669708D01*
X668886Y132022D01*
Y147942D01*
X668890Y147946D01*
Y148855D01*
X669172Y149137D01*
X670454D01*
X671735Y147856D01*
X671745Y147792D01*
G03X672989Y146548I1483J239D01*
G01X673053Y146538D01*
X674402Y145189D01*
Y140809D01*
X675361Y139850D01*
X704500D01*
X706750Y142100D01*
Y168199D01*
X706852Y168256D01*
G03X707312Y169042I-442J786D01*
G01Y170642D01*
G03X706852Y171428I-902J0D01*
G01X706750Y171485D01*
Y173750D01*
X707906Y174906D01*
X709446D01*
Y176446D01*
X709600Y176600D01*
Y180500D01*
X708550Y181550D01*
X705746D01*
X705396Y181900D01*
X684800D01*
X683700Y180800D01*
Y178900D01*
X683315Y178515D01*
X679223D01*
X678523Y179215D01*
Y190573D01*
X678372Y190724D01*
X673076D01*
X671054Y188702D01*
Y171891D01*
G02X670533Y171509I-400J-1D01*
G03X669527Y171475I-455J-1431D01*
G01X669492Y171462D01*
X667843D01*
G03Y168658I0J-1402D01*
G01X669586D01*
X669616Y168649D01*
G03X670540I462J1429D01*
G01X670570Y168658D01*
X670641D01*
X670686Y168704D01*
X670718Y168719D01*
G03X670763Y168741I-637J1360D01*
G01X670806Y168763D01*
X671054D01*
Y160563D01*
X672894Y158723D01*
X674082D01*
X674600Y158205D01*
Y149750D01*
X674379Y149529D01*
X673331D01*
G03X673125I-103J-1498D01*
G01X672050D01*
X671501Y150078D01*
Y150699D01*
X671510Y150729D01*
G03Y151633I-1432J452D01*
G01X671501Y151663D01*
Y152299D01*
X670700Y153100D01*
X663100D01*
X662200Y152200D01*
X659583D01*
X659131Y152652D01*
Y157431D01*
X660842Y159142D01*
X660903Y159153D01*
G03X662107Y160357I-273J1477D01*
G01X662118Y160418D01*
X663302Y161602D01*
Y162760D01*
G03Y166236I-1658J1738D01*
G01Y167598D01*
X662384Y168516D01*
Y186516D01*
X659300Y189600D01*
Y197005D01*
G03X659669Y198904I-2187J1410D01*
G01X659649Y199008D01*
X663141Y202500D01*
Y206147D01*
X664809Y207815D01*
X667397D01*
X667426Y207806D01*
G03X668880I727J2289D01*
G01X668909Y207815D01*
X676952D01*
X677634Y207134D01*
Y197366D01*
X678400Y196600D01*
X682600D01*
X683280Y195920D01*
Y194187D01*
X683300Y194168D01*
Y193023D01*
X683523Y192800D01*
Y192215D01*
X684823Y190915D01*
X684850D01*
X685550Y190215D01*
Y188500D01*
X685850Y188200D01*
X688150D01*
X688650Y188700D01*
Y190950D01*
X688394Y191206D01*
Y191540D01*
X687854Y192079D01*
Y193046D01*
X688023Y193215D01*
X689062D01*
G37*
G36*
G01X658225Y127300D02*
X658182Y127323D01*
G03X657481Y127496I-702J-1339D01*
G01X656704D01*
X656300Y127900D01*
Y130100D01*
X656900Y130700D01*
X658100D01*
X659000Y131600D01*
Y133200D01*
X659400Y133600D01*
X661600D01*
X662000Y133200D01*
Y127700D01*
X661600Y127300D01*
X658225D01*
G37*
G36*
G01X675833Y140378D02*
X675200Y141011D01*
Y157067D01*
X675184Y157084D01*
Y158769D01*
X674619Y159334D01*
X673166D01*
X672000Y160500D01*
Y165218D01*
G02X672574Y165578I400J0D01*
G03X674291Y165867I655J1351D01*
G01X675897Y167474D01*
X676547D01*
G03X677693Y169946I0J1502D01*
G02Y170204I152J129D01*
G03X676547Y172676I-1146J970D01*
G01X675904D01*
X674291Y174290D01*
G03X672574Y174579I-1062J-1062D01*
G02X672000Y174939I-174J360D01*
G01Y188843D01*
X673365Y190208D01*
X677909D01*
X678017Y190100D01*
Y184122D01*
G02X677357Y183818I-400J0D01*
G03Y181538I-978J-1140D01*
G02X678017Y181234I260J-304D01*
G01Y178749D01*
X678087Y178679D01*
X678952Y177815D01*
X683515D01*
X684200Y178500D01*
Y178691D01*
X684202Y178692D01*
Y180102D01*
X684950Y180850D01*
X690463D01*
G02X690813Y180256I0J-400D01*
G03X693439I1313J-729D01*
G02X693789Y180850I350J194D01*
G01X699912D01*
G02X700262Y180256I0J-400D01*
G03X702888I1313J-729D01*
G02X703238Y180850I350J194D01*
G01X708050D01*
X708408Y180492D01*
Y176600D01*
X706200Y174392D01*
Y172567D01*
X706208Y172558D01*
Y142600D01*
X703986Y140378D01*
X697014D01*
X696990Y140384D01*
G03X696818Y140406I-174J-680D01*
G01X696018D01*
G03X695846Y140384I2J-702D01*
G01X695822Y140378D01*
X694785D01*
X694761Y140384D01*
G03X694592Y140404I-166J-681D01*
G01X693792D01*
G03X693623Y140384I-3J-701D01*
G01X693599Y140378D01*
X675833D01*
G37*
G36*
G01X673183Y131244D02*
X672860Y131567D01*
Y133749D01*
X673045Y133934D01*
X676328D01*
G03X676430I51J1501D01*
G01X682628D01*
G03X682730I51J1501D01*
G01X688927D01*
G03X689029I51J1501D01*
G01X689864D01*
X689980Y133818D01*
Y131384D01*
X689840Y131244D01*
X673183D01*
G37*
G36*
G01X663360Y131200D02*
X662730Y131830D01*
Y133670D01*
X661875Y134525D01*
X657375D01*
X656500Y135400D01*
Y149400D01*
X656700Y149600D01*
X658000D01*
X659000Y150600D01*
Y151400D01*
X659298Y151698D01*
X662408D01*
X662409Y151700D01*
X662600D01*
X663200Y152300D01*
X668300D01*
X668600Y152000D01*
Y151449D01*
X668597Y151432D01*
G03Y150930I1481J-251D01*
G01X668600Y150913D01*
Y149877D01*
X668096Y149373D01*
Y146510D01*
G02X667526Y146148I-400J0D01*
G03X667775Y143763I-598J-1268D01*
G02X668096Y143604I121J-159D01*
G01Y143344D01*
X668384Y143056D01*
Y140163D01*
G02X667762Y139830I-400J-1D01*
G03Y137332I-834J-1249D01*
G02X668384Y136999I222J-332D01*
G01Y132484D01*
X667100Y131200D01*
X663360D01*
G37*
G36*
G01X652500Y114600D02*
X649200D01*
X648800Y115000D01*
Y121200D01*
X650000Y122400D01*
Y133400D01*
X650300Y133700D01*
X652200D01*
X652800Y133100D01*
Y114900D01*
X652500Y114600D01*
G37*
G36*
G01X657250Y231700D02*
X656750Y232200D01*
Y237196D01*
X656756Y237220D01*
G03X656802Y237600I-1556J381D01*
G01Y239200D01*
G03X656756Y239580I-1602J-1D01*
G01X656750Y239604D01*
Y252750D01*
X657766Y253766D01*
X670734D01*
X671000Y253500D01*
Y249000D01*
X670600Y248600D01*
X669865D01*
G03X669800Y248602I-82J-1599D01*
G01X668200D01*
G03X668135Y248600I17J-1601D01*
G01X665100D01*
X664500Y248000D01*
Y232200D01*
X664000Y231700D01*
X657250D01*
G37*
G36*
G01X651000Y233000D02*
X650000Y234000D01*
Y261750D01*
X650550Y262300D01*
X651235D01*
G03X651300Y262298I82J1599D01*
G01X652700D01*
G03X652765Y262300I-17J1601D01*
G01X660200D01*
X661000Y261500D01*
Y256000D01*
X660000Y255000D01*
X657000D01*
X655500Y253500D01*
Y236262D01*
X655489Y236230D01*
G03X655398Y235700I1511J-532D01*
G01Y233700D01*
G03X655409Y233516I1602J3D01*
G01X655420Y233420D01*
X655000Y233000D01*
X651000D01*
G37*
G36*
G01X666100Y236900D02*
X665748Y237252D01*
Y246952D01*
X666195Y247398D01*
X670388D01*
X670423Y247363D01*
X676017D01*
X676370Y247010D01*
Y240883D01*
X676364Y240859D01*
G03Y239789I2136J-535D01*
G01X676370Y239765D01*
Y237670D01*
X675600Y236900D01*
X666100D01*
G37*
G36*
G01X643500Y233000D02*
X643102Y233398D01*
Y253598D01*
X643000Y253699D01*
Y254500D01*
X641500Y256000D01*
X637000D01*
X636500Y256500D01*
Y261500D01*
X637300Y262300D01*
X644735D01*
G03X644800Y262298I82J1599D01*
G01X646200D01*
G03X646265Y262300I-17J1601D01*
G01X647450D01*
X648500Y261250D01*
Y233500D01*
X648000Y233000D01*
X643500D01*
G37*
G36*
G01X678453Y374613D02*
X672501Y368661D01*
Y343231D01*
X668164Y338894D01*
Y322664D01*
X667100Y321600D01*
X649500D01*
X647879Y323221D01*
Y367979D01*
X648400Y368500D01*
X661144D01*
X667058Y374414D01*
X667113Y374428D01*
G03X668286Y375601I-382J1555D01*
G01X668300Y375656D01*
X668563Y375919D01*
Y376665D01*
X672778Y380880D01*
X672859Y380882D01*
G03X674287Y381817I-28J1601D01*
G01X678208D01*
X678492Y381533D01*
Y374710D01*
X678477Y374673D01*
G03X678468Y374651I2219J-920D01*
G01X678453Y374613D01*
G37*
G36*
G01X703800Y326700D02*
X694500Y336000D01*
Y366300D01*
X702300Y374100D01*
X709200D01*
X718500Y383400D01*
X742800D01*
X744300Y381900D01*
Y370200D01*
X734400Y360300D01*
X725700D01*
X722500Y357100D01*
Y356699D01*
X722498Y356698D01*
Y327998D01*
X721200Y326700D01*
X703800D01*
G37*
G36*
G01X645700Y360800D02*
X636100D01*
X635550Y361350D01*
Y367450D01*
X636100Y368000D01*
X645600D01*
X645900Y367700D01*
Y361000D01*
X645700Y360800D01*
G37*
G36*
G01X694700Y481600D02*
X697900Y478400D01*
Y466050D01*
X700050Y463900D01*
Y452450D01*
X698950Y451350D01*
X687300D01*
X686900Y451750D01*
Y459701D01*
X686902Y459702D01*
Y479225D01*
X686903Y479236D01*
G03X686911Y479339I-1592J175D01*
G01X686915Y479415D01*
X686925Y479425D01*
Y481325D01*
X687200Y481600D01*
X694700D01*
G37*
G36*
G01X668700Y459400D02*
X666100Y462000D01*
Y479100D01*
X668400Y481400D01*
X685550D01*
X685700Y481250D01*
Y460200D01*
X684900Y459400D01*
X668700D01*
G37*
G36*
G01X751418Y80630D02*
X750732Y81317D01*
Y87243D01*
X751489Y88000D01*
X753350D01*
X753800Y87550D01*
X759899D01*
G02X760293Y87080I0J-400D01*
G03X760268Y86800I1577J-282D01*
G01Y85400D01*
G03X760700Y84306I1601J0D01*
G01Y83694D01*
G03X760268Y82600I1169J-1094D01*
G01Y81200D01*
G03X760295Y80912I1602J5D01*
G01X760314Y80809D01*
X760135Y80630D01*
X751418D01*
G37*
G36*
G01X724500Y327000D02*
X723700Y327800D01*
Y328705D01*
X723701Y328713D01*
G03X723706Y328838I-1597J126D01*
G01Y330438D01*
G03X723701Y330563I-1602J-1D01*
G01X723700Y330571D01*
Y332705D01*
X723701Y332713D01*
G03X723706Y332838I-1597J126D01*
G01Y334238D01*
G03X723701Y334363I-1602J-1D01*
G01X723700Y334371D01*
Y356200D01*
X724500Y357000D01*
X737700D01*
X738600Y356100D01*
Y328200D01*
X737400Y327000D01*
X724500D01*
G37*
G36*
G01X742400Y459400D02*
X729900D01*
X728400Y460900D01*
Y478900D01*
X729900Y480400D01*
X741900D01*
X743400Y478900D01*
Y460400D01*
X742400Y459400D01*
G37*
G36*
G01X719900Y451900D02*
X702400D01*
X701600Y452700D01*
Y464850D01*
X699900Y466550D01*
Y478400D01*
X701400Y479900D01*
X717400D01*
X720400Y476900D01*
Y452400D01*
X719900Y451900D01*
G37*
G36*
G01X773363Y112060D02*
X773342Y112065D01*
G03X773000Y112102I-342J-1565D01*
G01X771000D01*
G03X770823Y112092I2J-1602D01*
G01X770728Y112081D01*
X770373Y112436D01*
Y124927D01*
X770533Y125087D01*
X788945D01*
X790293Y123739D01*
Y120131D01*
X785941Y115779D01*
Y112854D01*
X785147Y112060D01*
X773363D01*
G37*
G36*
G01X794350Y104650D02*
X794122Y104877D01*
Y115123D01*
X794500Y115500D01*
X806100D01*
X806400Y115200D01*
Y105100D01*
X805950Y104650D01*
X794350D01*
G37*
G36*
G01X780300Y83100D02*
X779500Y83900D01*
Y92500D01*
X779900Y92900D01*
X780235D01*
G03X780300Y92898I82J1599D01*
G01X781700D01*
G03X781765Y92900I-17J1601D01*
G01X784585D01*
G03X784650Y92898I82J1599D01*
G01X786050D01*
G03X786119Y92900I-12J1602D01*
G01X786200D01*
X786475Y92625D01*
Y87338D01*
G03X786185Y86742I1812J-1250D01*
G01X786141Y86602D01*
X784650D01*
G03X784197Y86536I2J-1602D01*
G01X784170Y86528D01*
X783578D01*
X783050Y86000D01*
Y85065D01*
G03X783048Y85000I1599J-82D01*
G01Y83548D01*
X782600Y83100D01*
X780300D01*
G37*
G36*
G01X787404Y115003D02*
X788290Y115889D01*
X792288D01*
X792921Y115256D01*
Y107468D01*
X792919Y107452D01*
G03X792898Y107200I1580J-259D01*
G01Y105800D01*
G03X792919Y105548I1601J7D01*
G01X792921Y105532D01*
Y105031D01*
X792595Y104705D01*
X766300D01*
X765552Y105453D01*
Y114599D01*
X765853Y114900D01*
X768900D01*
X769000Y114800D01*
Y111900D01*
X769921Y110979D01*
X770131D01*
X770251Y110858D01*
X785645D01*
X785765Y110979D01*
X787179D01*
X787404Y111204D01*
Y115003D01*
G37*
G36*
G01X805746Y121098D02*
X800082D01*
X799115Y122065D01*
Y133361D01*
X801267Y135513D01*
Y138304D01*
X801454Y138491D01*
X806047D01*
X806446Y138092D01*
Y121798D01*
X805746Y121098D01*
G37*
G36*
G01X799049Y168614D02*
X798449Y169214D01*
Y179443D01*
X798759Y179753D01*
X799520D01*
X799537Y179750D01*
G03X799800Y179728I265J1580D01*
G01X801400D01*
G03X801663Y179750I-2J1602D01*
G01X801680Y179753D01*
X803420D01*
X803437Y179750D01*
G03X803700Y179728I265J1580D01*
G01X805300D01*
G03X805563Y179750I-2J1602D01*
G01X805580Y179753D01*
X805936D01*
X806479Y179210D01*
Y169780D01*
X805313Y168614D01*
X799049D01*
G37*
G36*
G01X797199Y120600D02*
X792564D01*
X791501Y121663D01*
Y124374D01*
X789573Y126302D01*
X768502D01*
X767550Y127254D01*
Y131000D01*
X769150Y132600D01*
X770800D01*
X771479Y133279D01*
X780071D01*
X781452Y131898D01*
X797606D01*
X797905Y131599D01*
Y121306D01*
X797199Y120600D01*
G37*
G36*
G01X797653Y184962D02*
X797407Y185208D01*
X794357D01*
X793964Y185601D01*
Y187703D01*
X794332Y188071D01*
X805122D01*
X806378Y186815D01*
Y181546D01*
X805792Y180960D01*
X799230D01*
X798531Y181660D01*
Y184107D01*
X798127Y184511D01*
G03X797672Y184950I-1318J-910D01*
G01X797653Y184962D01*
G37*
%LPC*%
G75*
G36*
G01X304702Y224998D02*
Y204002D01*
X302498Y201798D01*
X288002D01*
X284298Y205502D01*
Y224498D01*
X286002Y226202D01*
X303498D01*
X304702Y224998D01*
G37*
G36*
G01X304202Y182998D02*
Y162502D01*
X302998Y161298D01*
X287002D01*
X283298Y165002D01*
Y182998D01*
X284502Y184202D01*
X302998D01*
X304202Y182998D01*
G37*
G36*
G01X493800Y289200D02*
Y288400D01*
X493000D01*
X492600Y288200D01*
X491800D01*
Y289000D01*
X492600D01*
X493000Y289200D01*
X493800D01*
G37*
G36*
G01X484900Y284900D02*
X485150Y284850D01*
X485950D01*
Y284050D01*
X485150D01*
X484900Y284100D01*
X484100D01*
Y284900D01*
X484900D01*
G37*
G36*
G01X493428Y284378D02*
Y283987D01*
X493440Y283954D01*
G02X490812I-1314J-489D01*
G01X490824Y283987D01*
Y285456D01*
X490847Y285478D01*
X490852Y285552D01*
G02X490960Y285977I1298J-104D01*
G02X491374Y286495I690J-127D01*
G02X492926I776J-1045D01*
G02X493340Y285977I-276J-645D01*
G02X493452Y285450I-1190J-528D01*
G01Y284402D01*
X493428Y284378D01*
G37*
G36*
G01X489352Y281500D02*
Y280312D01*
G02X486914Y278944I-1163J-784D01*
G01X486899Y278977D01*
X486748Y279128D01*
Y281500D01*
G02X486860Y282027I1302J-1D01*
G02X487274Y282545I690J-127D01*
G02X488826I776J-1045D01*
G02X489240Y282027I-276J-645D01*
G02X489352Y281500I-1190J-528D01*
G37*
G36*
G01X493216Y272914D02*
G02X492876Y272605I-616J336D01*
G02X491324I-776J1045D01*
G02X490910Y273123I276J645D01*
G02X490821Y273891I1190J527D01*
G01X490824Y273910D01*
Y275069D01*
X490812Y275102D01*
G02X490833Y276133I1314J489D01*
G01X490848Y276170D01*
Y277500D01*
G02X490960Y278027I1302J-1D01*
G02X491374Y278545I690J-127D01*
G02X492926I776J-1045D01*
G02X493340Y278027I-276J-645D01*
G02X493452Y277500I-1190J-528D01*
G01Y276049D01*
X493461Y276019D01*
G02Y275163I-1335J-428D01*
G01X493452Y275133D01*
Y275076D01*
X493428Y275052D01*
Y273137D01*
X493229Y272939D01*
X493216Y272914D01*
G37*
G36*
G01X489390Y269173D02*
G02X488976Y268655I-690J127D01*
G02X487424I-776J1045D01*
G02X487084Y268964I276J645D01*
G01X487071Y268989D01*
X486888Y269171D01*
Y271129D01*
X486876Y271163D01*
G02X489464Y272238I1313J492D01*
G01X489479Y272205D01*
X489492Y272192D01*
Y272174D01*
X489504Y272140D01*
G02Y271168I-1315J-486D01*
G01X489492Y271134D01*
Y269861D01*
X489493Y269850D01*
G02X489390Y269173I-1293J-150D01*
G37*
G36*
G01X493216Y264864D02*
G02X492876Y264555I-616J336D01*
G02X491324I-776J1045D01*
G02X490910Y265073I276J645D01*
G02X490821Y265841I1190J527D01*
G01X490824Y265860D01*
Y267195D01*
X490812Y267228D01*
G02X493440I1314J489D01*
G01X493428Y267195D01*
Y265087D01*
X493229Y264889D01*
X493216Y264864D01*
G37*
G36*
G01X489390Y253373D02*
G02X488976Y252855I-690J127D01*
G02X487424I-776J1045D01*
G02X487084Y253164I276J645D01*
G01X487071Y253189D01*
X486888Y253372D01*
Y255384D01*
X486875Y255417D01*
G02X487131Y256826I1314J489D01*
G03X487140Y257078I-151J132D01*
G02X487084Y257164I558J425D01*
G01X487071Y257189D01*
X486888Y257372D01*
Y259321D01*
X486875Y259354D01*
G02Y260332I1314J489D01*
G01X486888Y260365D01*
Y262478D01*
X487071Y262661D01*
X487084Y262686D01*
G02X487424Y262995I616J-336D01*
G02X488976I776J-1045D01*
G02X489390Y262477I-276J-645D01*
G02X489492Y261793I-1190J-527D01*
G01X489490Y261781D01*
Y260365D01*
X489503Y260332D01*
G02Y259354I-1314J-489D01*
G01X489490Y259321D01*
Y258069D01*
X489492Y258057D01*
G02X489390Y257373I-1292J-157D01*
G02X489252Y257067I-690J127D01*
G03X489257Y256814I157J-123D01*
G02X489503Y255417I-1068J-908D01*
G01X489490Y255384D01*
Y254069D01*
X489492Y254057D01*
G02X489390Y253373I-1292J-157D01*
G37*
G36*
G01Y245473D02*
G02X488976Y244955I-690J127D01*
G02X487424I-776J1045D01*
G02X487084Y245264I276J645D01*
G01X487071Y245289D01*
X486888Y245472D01*
Y247510D01*
X486875Y247543D01*
G02Y248521I1314J489D01*
G01X486888Y248554D01*
Y250528D01*
X487071Y250711D01*
X487084Y250736D01*
G02X487424Y251045I616J-336D01*
G02X488976I776J-1045D01*
G02X489390Y250527I-276J-645D01*
G02X489492Y249843I-1190J-527D01*
G01X489490Y249831D01*
Y248554D01*
X489503Y248521D01*
G02Y247543I-1314J-489D01*
G01X489490Y247510D01*
Y246169D01*
X489492Y246157D01*
G02X489390Y245473I-1292J-157D01*
G37*
G36*
G01X489452Y242150D02*
Y240769D01*
X489469Y240730D01*
G02X486914Y239574I-1280J-572D01*
G01X486899Y239607D01*
X486848Y239658D01*
Y239746D01*
X486841Y239773D01*
G02Y240543I1348J385D01*
G01X486848Y240570D01*
Y242150D01*
G02X486960Y242677I1302J-1D01*
G02X487374Y243195I690J-127D01*
G02X488926I776J-1045D01*
G02X489340Y242677I-276J-645D01*
G02X489452Y242150I-1190J-528D01*
G37*
G36*
G01X427589Y234400D02*
X482865D01*
X483231Y234033D01*
X483240Y234026D01*
G02X483350Y233916I-438J-548D01*
G01X483357Y233907D01*
X483758Y233506D01*
Y230855D01*
X482853Y229950D01*
X427779D01*
X426888Y230840D01*
Y233699D01*
X427589Y234400D01*
G37*
G36*
G01X479500Y283000D02*
X479900Y282650D01*
X480700D01*
Y281850D01*
X479900D01*
X479500Y282200D01*
X478700D01*
Y283000D01*
X479500D01*
G37*
G36*
G01X456900Y281502D02*
X457000Y281500D01*
X457800D01*
Y280700D01*
X457000D01*
X456900Y280702D01*
X456100D01*
Y281502D01*
X456900D01*
G37*
G36*
G01X455500D02*
Y280702D01*
X454700D01*
X454600Y280700D01*
X453800D01*
Y281500D01*
X454600D01*
X454700Y281502D01*
X455500D01*
G37*
G36*
G01X456900Y285302D02*
X457000Y285300D01*
X457800D01*
Y284500D01*
X457000D01*
X456900Y284502D01*
X456100D01*
Y285302D01*
X456900D01*
G37*
G36*
G01X455500D02*
Y284502D01*
X454700D01*
X454600Y284500D01*
X453800D01*
Y285300D01*
X454600D01*
X454700Y285302D01*
X455500D01*
G37*
G36*
G01X640350Y134100D02*
Y133300D01*
X640300Y132900D01*
Y132100D01*
X639500D01*
Y132900D01*
X639550Y133300D01*
Y134100D01*
X640350D01*
G37*
G36*
G01X604226Y237652D02*
Y236852D01*
X604126Y236552D01*
Y235752D01*
X603326D01*
Y236552D01*
X603426Y236852D01*
Y237652D01*
X604226D01*
G37*
G36*
G01X639800Y237600D02*
Y236800D01*
X639900Y236500D01*
Y235700D01*
X639100D01*
Y236500D01*
X639000Y236800D01*
Y237600D01*
X639800D01*
G37*
G36*
G01X610226Y237652D02*
Y236852D01*
X610126Y236552D01*
Y235752D01*
X609326D01*
Y236552D01*
X609426Y236852D01*
Y237652D01*
X610226D01*
G37*
G36*
G01X646350Y134100D02*
Y133300D01*
X646300Y132900D01*
Y132100D01*
X645500D01*
Y132900D01*
X645550Y133300D01*
Y134100D01*
X646350D01*
G37*
G36*
G01X696118Y138804D02*
Y138004D01*
X695318D01*
X695292Y138003D01*
X694492D01*
Y138803D01*
X695292D01*
X695318Y138804D01*
X696118D01*
G37*
G36*
G01X688998Y138512D02*
X689000Y138500D01*
X689800D01*
Y137700D01*
X689000D01*
X688998Y137712D01*
X688198D01*
Y138512D01*
X688998D01*
G37*
G36*
G01X672944Y195715D02*
Y192443D01*
X671352Y190851D01*
G02X668804Y193399I-1274J1274D01*
G01X669340Y193935D01*
Y195715D01*
G02X669386Y196115I1801J-5D01*
G01X669390Y196137D01*
Y196515D01*
G02X669931Y197341I901J0D01*
G01X670050Y197393D01*
Y200715D01*
G02X672854I1402J0D01*
G01Y196278D01*
X672862Y196249D01*
G02X672944Y195715I-1719J-537D01*
G37*
G36*
G01X664908Y190722D02*
Y189280D01*
G02X662106I-1401J0D01*
G01Y191251D01*
X661660Y191696D01*
Y195705D01*
G02X661706Y196105I1801J-5D01*
G01X661710Y196127D01*
Y196505D01*
G02X662612Y197406I902J-1D01*
G01X662869D01*
X662900Y197416D01*
G02X664024I562J-1711D01*
G01X664055Y197406D01*
X664212D01*
G02X665114Y196505I1J-901D01*
G01Y196426D01*
X665128Y196389D01*
G02X665264Y195705I-1665J-687D01*
G01Y193146D01*
G02X664908Y190722I-1485J-1020D01*
G37*
G36*
G01X710962Y174729D02*
X711040Y174732D01*
X713643Y177335D01*
X713658Y177369D01*
G02X714257Y174427I2382J-1047D01*
G03X713700Y174418I-274J-292D01*
G01X712527Y173245D01*
X712524Y173167D01*
G02X710962Y174729I-1501J61D01*
G37*
G36*
G01X696118Y142604D02*
Y141804D01*
X695318D01*
X695292Y141803D01*
X694492D01*
Y142603D01*
X695292D01*
X695318Y142604D01*
X696118D01*
G37*
G36*
G01X688998Y142312D02*
X689000Y142300D01*
X689800D01*
Y141500D01*
X689000D01*
X688998Y141512D01*
X688198D01*
Y142312D01*
X688998D01*
G37*
G36*
G01X699800Y173655D02*
X700192Y174048D01*
X700905Y174762D01*
X702165D01*
X702621Y174305D01*
X702622Y174304D01*
G02X702651Y174275I-1047J-1076D01*
G01X702652Y174274D01*
X703510Y173416D01*
Y172700D01*
X703676Y172533D01*
Y145292D01*
X702983Y144598D01*
X700244D01*
X699800Y145042D01*
Y173655D01*
G37*
G36*
G01X694651Y174740D02*
X695884D01*
X696280Y174344D01*
G02X696391Y174233I-1005J-1116D01*
G01X696788Y173836D01*
Y145079D01*
X696258Y144548D01*
X693892D01*
X693448Y144992D01*
Y173538D01*
X694651Y174740D01*
G37*
G36*
G01X684402Y173958D02*
Y143992D01*
X683808Y143398D01*
X681242D01*
X680847Y143794D01*
G03X680567Y143797I-142J-141D01*
G02X680097Y146269I-1041J1083D01*
G03X680648Y146639I151J370D01*
G01Y162019D01*
G03X680097Y162389I-400J0D01*
G02Y165169I-570J1390D01*
G03X680648Y165539I151J370D01*
G01Y174008D01*
X681442Y174802D01*
X683558D01*
X684402Y173958D01*
G37*
G36*
G01X661472Y139827D02*
G02X659786I-843J-1243D01*
G03Y140489I-225J331D01*
G02X659788Y142976I843J1243D01*
G03Y143639I-224J332D01*
G02X661470I841J1244D01*
G03Y142976I224J-331D01*
G02X661472Y140489I-841J-1244D01*
G03Y139827I225J-331D01*
G37*
G36*
G01X659600Y237600D02*
Y236800D01*
X659400Y236500D01*
Y235700D01*
X658600D01*
Y236500D01*
X658800Y236800D01*
Y237600D01*
X659600D01*
G37*
G36*
G01X653600D02*
Y236800D01*
X653400Y236500D01*
Y235700D01*
X652600D01*
Y236500D01*
X652800Y236800D01*
Y237600D01*
X653600D01*
G37*
G36*
G01X645800D02*
Y236800D01*
X645900Y236500D01*
Y235700D01*
X645100D01*
Y236500D01*
X645000Y236800D01*
Y237600D01*
X645800D01*
G37*
G54D99*
X420323Y288848D03*
X773407Y122693D03*
Y128693D03*
G54D103*
X708352Y151135D03*
X708321Y157519D03*
X708362Y163813D03*
X704552Y151135D03*
X698150Y151140D03*
X691800Y151150D03*
X691885Y157436D03*
X698144Y157443D03*
X704521Y157519D03*
X686100Y163730D03*
X691812Y163765D03*
X704562Y163813D03*
X698123Y163814D03*
X686050Y170030D03*
X691650Y170050D03*
X679547Y170075D03*
G54D101*
X646594Y210875D03*
X670078Y157480D03*
X688976Y148031D03*
Y154330D03*
Y160629D03*
Y166929D03*
Y173228D03*
X663778Y135431D03*
G54D102*
X648483Y110146D03*
G54D98*
X452350Y281100D03*
X429150Y281600D03*
X452350Y284900D03*
G54D97*
X467813Y279174D03*
Y275374D03*
G54D96*
X488300Y228650D03*
X484082Y263945D03*
X492100Y228650D03*
X422845Y232300D03*
X480282Y263945D03*
X507538Y224540D03*
X511338D03*
X624026Y236702D03*
X618026D03*
X645517Y117864D03*
X677952Y152665D03*
X651517Y117864D03*
G54D94*
X323537Y274170D03*
Y280170D03*
X428950Y228200D03*
X436850D03*
X444650D03*
X452900D03*
X460400D03*
X468300D03*
X476150D03*
X484000D03*
X429800Y235950D03*
X437250D03*
X445150D03*
X453090D03*
X460950D03*
X468850D03*
X476650D03*
X421950Y224400D03*
X428950D03*
X436850D03*
X444650D03*
X452900D03*
X460400D03*
X468300D03*
X476150D03*
X484000D03*
X444750Y251950D03*
X452700D03*
X460700D03*
X444650Y259350D03*
X453300D03*
X460750D03*
X444750Y268400D03*
X452750D03*
X460750D03*
X441250Y279000D03*
X448750D03*
X436650Y281200D03*
X464550D03*
X444750Y255750D03*
X452700D03*
X460700D03*
X444650Y263150D03*
X453300D03*
X460750D03*
X444750Y272200D03*
X452750D03*
X460750D03*
X441250Y275200D03*
X448750D03*
X436650Y285000D03*
X646998Y49095D03*
X650498D03*
X646998Y43095D03*
X650498D03*
G54D104*
X708355Y454712D03*
G54D95*
X492126Y248032D03*
X437007Y287402D03*
X440945D03*
X433070D03*
G54D100*
X507538Y216214D03*
X511338D03*
G54D93*
X154658Y417070D03*
Y419470D03*
X164438Y431170D03*
Y434570D03*
X170038Y431170D03*
X173438D03*
X170038Y434570D03*
X173438D03*
X148658Y417070D03*
Y419470D03*
X273000Y247700D03*
Y244300D03*
X273500Y226200D03*
Y222800D03*
Y206200D03*
Y202800D03*
X273000Y184700D03*
Y181300D03*
Y164700D03*
Y161300D03*
X273500Y142700D03*
Y139300D03*
X250000Y413800D03*
Y416200D03*
X282500Y142700D03*
X298800Y146000D03*
X302200D03*
X299300Y157500D03*
X302700D03*
X282000Y161300D03*
Y164700D03*
Y181300D03*
Y184700D03*
X298800Y188000D03*
X302200D03*
X298800Y197500D03*
X302200D03*
X298800Y200900D03*
X302200D03*
X282500Y202800D03*
Y206200D03*
Y222800D03*
Y226200D03*
X299300Y227100D03*
X302700D03*
X299300Y230500D03*
X302700D03*
X298800Y240000D03*
X302200D03*
X282000Y244300D03*
X298800Y137000D03*
X320587Y274170D03*
X298800Y249000D03*
X320587Y280170D03*
X317300Y288900D03*
X368489Y297441D03*
X371289D03*
X364389Y298841D03*
X364377Y303562D03*
X365777Y305362D03*
X368577D03*
X368768Y277287D03*
X365968D03*
X364568Y275787D03*
Y270741D03*
X368768Y269241D03*
X365968D03*
X368740Y249140D03*
X365940D03*
X364510Y247640D03*
X357122Y297141D03*
X357114Y305562D03*
X357198Y249344D03*
X357069Y269868D03*
X343400Y276570D03*
X357242Y277487D03*
X343400Y278970D03*
X422500Y228200D03*
X423900D03*
X427000D03*
X430900D03*
X434900D03*
X438800D03*
X442700D03*
X446600D03*
X450950D03*
X454850D03*
X458450D03*
X462350D03*
X466350D03*
X470250D03*
X474200D03*
X478100D03*
X482050D03*
X485950D03*
X488300Y230600D03*
X488317Y233508D03*
Y234908D03*
X427850Y235950D03*
X431750D03*
X435300D03*
X439200D03*
X443200D03*
X447100D03*
X451140D03*
X455040D03*
X459000D03*
X462900D03*
X466900D03*
X470800D03*
X474700D03*
X484100Y237400D03*
X488250Y237500D03*
X484100Y238800D03*
Y241400D03*
Y242800D03*
X491150Y242850D03*
X484100Y245300D03*
X491200D03*
X484100Y246700D03*
Y249250D03*
Y250650D03*
X491200Y250700D03*
X484100Y253200D03*
X491200D03*
X484100Y254600D03*
X491200D03*
X484100Y257100D03*
X491200Y257200D03*
X484100Y258500D03*
X491200Y258600D03*
Y261250D03*
X484082Y261995D03*
X491200Y262650D03*
X489100Y264900D03*
X484082Y265895D03*
X489100Y266300D03*
X484100Y268950D03*
Y270350D03*
X491200Y270400D03*
X484100Y272900D03*
Y274300D03*
X489100Y274350D03*
X489150Y276800D03*
X484100Y276900D03*
Y278300D03*
X491050Y280800D03*
X484100Y280850D03*
Y282250D03*
X486950Y284450D03*
X489150Y284750D03*
X420000Y224400D03*
X423900D03*
X427000D03*
X430900D03*
X434900D03*
X438800D03*
X442700D03*
X446600D03*
X450950D03*
X454850D03*
X458450D03*
X462350D03*
X466350D03*
X470250D03*
X474200D03*
X478100D03*
X482050D03*
X485950D03*
X402400Y225700D03*
X492100Y226700D03*
X410698Y228600D03*
X412098D03*
X492100Y230600D03*
X492117Y233508D03*
Y234908D03*
X492050Y237500D03*
Y238900D03*
X431000Y281600D03*
X450500Y281100D03*
X480300Y238800D03*
Y241400D03*
Y242800D03*
Y245300D03*
Y246700D03*
X471700Y248000D03*
X480300Y249250D03*
X471700Y250400D03*
X480300Y250650D03*
X466134Y251000D03*
X468934D03*
X442800Y251950D03*
X446700D03*
X450750D03*
X454650D03*
X458750D03*
X462650D03*
X480300Y253200D03*
X471600Y253600D03*
X480300Y254600D03*
X471600Y256000D03*
X480300Y257100D03*
X433018Y257127D03*
X480300Y258500D03*
X433018Y258527D03*
X442700Y259350D03*
X446600D03*
X451350D03*
X455250D03*
X458800D03*
X462700D03*
X471400Y261300D03*
X480282Y261995D03*
X471400Y263700D03*
X480282Y265895D03*
X466137Y267196D03*
X468937D03*
X442800Y268400D03*
X446700D03*
X450800D03*
X454700D03*
X458800D03*
X462700D03*
X480300Y268950D03*
X471500Y269400D03*
X480300Y270350D03*
Y272900D03*
X432267Y274053D03*
X480300Y274300D03*
Y276900D03*
Y278300D03*
X461853Y278970D03*
X463253D03*
X439300Y279000D03*
X443200D03*
X446800D03*
X450700D03*
X454000D03*
X455400D03*
X458000D03*
X459400D03*
X465958Y279174D03*
X469668D03*
X471400Y279900D03*
X480300Y280850D03*
X438600Y281200D03*
X443000D03*
X444400D03*
X445800D03*
X462600D03*
X471190Y281400D03*
X427300Y281600D03*
X473820Y282600D03*
X475220D03*
X477700D03*
X438018Y254501D03*
X442800Y255750D03*
X446700D03*
X450750D03*
X454650D03*
X458750D03*
X462650D03*
X436818Y257127D03*
Y258527D03*
X442700Y263150D03*
X446600D03*
X451350D03*
X455250D03*
X458800D03*
X462700D03*
X433889Y268340D03*
X442800Y272200D03*
X446700D03*
X450800D03*
X454700D03*
X458800D03*
X462700D03*
X436067Y272653D03*
X466137Y273196D03*
X436067Y274053D03*
X461853Y275170D03*
X463253D03*
X439300Y275200D03*
X443200D03*
X446800D03*
X450700D03*
X454000D03*
X455400D03*
X458000D03*
X459400D03*
X465958Y275374D03*
X450500Y284900D03*
X434700Y285000D03*
X438600D03*
X443000D03*
X444400D03*
X445800D03*
X447200D03*
X469790Y285200D03*
X431000Y285400D03*
X423723Y288848D03*
X429270Y245079D03*
X431670D03*
X436800D03*
X439200D03*
X443650D03*
X446050D03*
X450300D03*
X452700D03*
X458300D03*
X460700D03*
X466400D03*
X468800D03*
X474300D03*
X476700D03*
X449741Y352740D03*
X441286Y352441D03*
X449741Y350540D03*
X507538Y214271D03*
X505722Y215276D03*
Y217800D03*
X507538Y218156D03*
Y222590D03*
X505722Y223150D03*
Y225650D03*
X507538Y226490D03*
Y230389D03*
X505722Y230991D03*
X507538Y231789D03*
Y233048D03*
X505722Y233519D03*
X507538Y234448D03*
X511338Y214271D03*
Y218156D03*
Y222590D03*
Y226490D03*
Y230389D03*
Y231789D03*
Y233048D03*
Y234448D03*
X498306Y346331D03*
X514617Y346346D03*
X516417D03*
X518617D03*
X520422D03*
X522622D03*
X524422D03*
X526622D03*
X528522D03*
X517400Y351200D03*
X519600D03*
X521400D03*
X523600D03*
X507100Y356100D03*
X508900D03*
X511100D03*
X458841Y355255D03*
Y357455D03*
X515400Y455600D03*
Y458000D03*
X515650Y474900D03*
Y477100D03*
X521400Y458000D03*
X540795Y469683D03*
X521250Y474900D03*
X523150D03*
X521250Y477100D03*
X523150D03*
X643750Y35500D03*
X646150D03*
X644048Y49095D03*
X658750Y51300D03*
X660950D03*
X630400Y104200D03*
X632600D03*
X630400Y109800D03*
X632600D03*
X630081Y127008D03*
X633481D03*
X639900Y129700D03*
X639950Y136100D03*
X639923Y143711D03*
Y146111D03*
X639900Y147600D03*
Y150000D03*
X630081Y136008D03*
X603726Y233752D03*
X603826Y240052D03*
X602526Y250752D03*
X639400Y239600D03*
X624026Y240052D03*
X637500Y250300D03*
X640900D03*
X622626Y250752D03*
X626026D03*
X625100Y207800D03*
X626900D03*
X629100D03*
X630900D03*
X633100D03*
X634900D03*
X637100D03*
X638900D03*
X641100D03*
X642900D03*
X645100D03*
X646900D03*
X649100D03*
X650900D03*
X619126Y260452D03*
X616926D03*
X617026Y254152D03*
Y250752D03*
X618026Y240052D03*
Y233752D03*
X609726D03*
X609826Y240052D03*
X611526Y250752D03*
Y254152D03*
X610426Y260452D03*
X612626D03*
X644400Y265700D03*
X646600D03*
X650900D03*
X653100D03*
X610426Y266052D03*
X612626D03*
X616926D03*
X619126D03*
X643750Y41500D03*
X646150D03*
X654851Y41993D03*
X644048Y43095D03*
X653448D03*
X658945Y22214D03*
X648483Y111996D03*
X645517Y114914D03*
Y120814D03*
X646500Y124450D03*
Y127250D03*
X645900Y129700D03*
X645950Y136100D03*
X646454Y137391D03*
Y139791D03*
X645923Y143711D03*
Y146111D03*
X645900Y147600D03*
X671952Y153215D03*
X673187Y136186D03*
X674587D03*
X679971Y136232D03*
X681371D03*
X685936Y136246D03*
X687336D03*
X671977Y136518D03*
X704947Y137306D03*
X690800Y138100D03*
X682998Y138105D03*
X684398D03*
X687198Y138112D03*
X693492Y138403D03*
X697118Y138404D03*
X671918Y140625D03*
Y143025D03*
X709788Y144127D03*
X719142Y144465D03*
Y145865D03*
X709788Y146527D03*
X708352Y149335D03*
X719142Y150475D03*
Y151875D03*
X708352Y152935D03*
X661500Y154800D03*
X671952Y155615D03*
X708321Y155719D03*
X666100Y155900D03*
X719242Y157015D03*
Y158415D03*
X708321Y159319D03*
X708362Y162013D03*
X720000Y163500D03*
Y164900D03*
X708362Y165613D03*
X710410Y168642D03*
X719142Y169365D03*
Y170765D03*
X667143Y173060D03*
X668543D03*
X719142Y182095D03*
Y183495D03*
X715317Y184523D03*
X717717D03*
X664207Y186280D03*
X719142Y188485D03*
X683992Y189043D03*
X704435Y189077D03*
X698588Y189106D03*
X719142Y189885D03*
X704435Y190477D03*
X698588Y190506D03*
X694852Y193695D03*
X660737Y194108D03*
X668212Y194505D03*
X675892Y194515D03*
X681682Y194795D03*
X660737Y195508D03*
X668212Y196905D03*
X675892Y196915D03*
X670752Y203715D03*
X672152D03*
X659400Y129850D03*
X687300Y156150D03*
X687400Y152300D03*
X690800Y141900D03*
X682998Y141905D03*
X684398D03*
X687198Y141912D03*
X693492Y142203D03*
X697118Y142204D03*
X687402Y144115D03*
X691802Y145115D03*
X698152Y145165D03*
X691802Y146515D03*
X698152Y146565D03*
X704552Y149335D03*
X698150Y149340D03*
X691800Y149350D03*
X677952Y149715D03*
X704552Y152935D03*
X698150Y152940D03*
X691800Y152950D03*
X677952Y155615D03*
X691885Y155636D03*
X698144Y155643D03*
X704521Y155719D03*
X687300Y158550D03*
X691885Y159236D03*
X698144Y159243D03*
X704521Y159319D03*
X686100Y161930D03*
X691812Y161965D03*
X704562Y162013D03*
X698123Y162014D03*
X686100Y165530D03*
X691812Y165565D03*
X704562Y165613D03*
X698123Y165614D03*
X686050Y168230D03*
X691650Y168250D03*
X679547Y168275D03*
X686050Y171830D03*
X691650Y171850D03*
X679547Y171875D03*
X674587Y132386D03*
X679971Y132432D03*
X681371D03*
X685936Y132446D03*
X687336D03*
X665977Y134118D03*
X659100Y148800D03*
X661500D03*
X666100Y149900D03*
X651517Y120814D03*
X659000Y233300D03*
X659200Y239600D03*
X657600Y250300D03*
X661000D03*
X667800Y251000D03*
X653200Y239600D03*
X652000Y250300D03*
Y253700D03*
X650900Y260100D03*
X653100D03*
X667800Y245000D03*
X670200D03*
X645400Y239600D03*
X646500Y250300D03*
Y253700D03*
X644400Y260100D03*
X646600D03*
X674831Y378133D03*
X720104Y328438D03*
Y330838D03*
X720304Y332438D03*
Y334638D03*
X718604Y336838D03*
Y340238D03*
X689312Y479021D03*
X683312D03*
X758070Y83000D03*
Y85000D03*
X726104Y328438D03*
Y330838D03*
X725904Y332438D03*
Y334638D03*
X727604Y336838D03*
Y340238D03*
X773400Y114500D03*
X774800Y116000D03*
X778200D03*
X786407Y120893D03*
X776807Y122693D03*
X796300Y107600D03*
X784250Y88800D03*
X782100Y90700D03*
X784250D03*
X774800Y107000D03*
X778200D03*
X790700Y107600D03*
X770600Y108500D03*
X773400D03*
X803796Y136300D03*
X801307Y131693D03*
Y129493D03*
X799400Y177330D03*
X801800D03*
X803300D03*
X770407Y128693D03*
X776807D03*
X795707Y129493D03*
X786407Y129893D03*
X789807D03*
X799400Y183330D03*
X801800D03*
X803300D03*
%LPD*%
G75*
G36*
G01X302500Y162500D02*
X287500D01*
X284500Y165500D01*
Y182500D01*
X285000Y183000D01*
X302500D01*
X303000Y182500D01*
Y163000D01*
X302500Y162500D01*
G37*
G36*
G01X302000Y203000D02*
X288500D01*
X285500Y206000D01*
Y224000D01*
X286500Y225000D01*
X303000D01*
X303500Y224500D01*
Y204500D01*
X302000Y203000D01*
G37*
G36*
G01X482645Y230451D02*
X427987D01*
X427390Y231048D01*
Y233491D01*
X427797Y233898D01*
X482657D01*
X483257Y233298D01*
Y231063D01*
X482645Y230451D01*
G37*
G36*
G01X683600Y143900D02*
X681450D01*
X681150Y144200D01*
Y173800D01*
X681650Y174300D01*
X683350D01*
X683900Y173750D01*
Y144200D01*
X683600Y143900D01*
G37*
G36*
G01X696050Y145050D02*
X694100D01*
X693950Y145200D01*
Y173330D01*
X694859Y174239D01*
X695676D01*
X696287Y173628D01*
Y145287D01*
X696050Y145050D01*
G37*
G36*
G01X702775Y145100D02*
X700452D01*
X700302Y145250D01*
Y173448D01*
X700547Y173694D01*
X701113Y174260D01*
X701957D01*
X703008Y173208D01*
Y172492D01*
X703175Y172325D01*
Y145500D01*
X702775Y145100D01*
G37*
%LPC*%
G75*
G54D103*
X682250Y170030D03*
X682300Y163730D03*
X695450Y170050D03*
X701923Y163814D03*
X701944Y157443D03*
X701950Y151140D03*
G54D94*
X476650Y232150D03*
X468850D03*
X460950D03*
X453090D03*
X445150D03*
X437250D03*
X429800D03*
G54D93*
X298800Y179000D03*
X299300Y166500D03*
Y221500D03*
X302200Y206500D03*
X298800D03*
X481702Y232178D03*
X478600Y232150D03*
X474700D03*
X470800D03*
X466900D03*
X462900D03*
X459000D03*
X455040D03*
X451140D03*
X447100D03*
X443200D03*
X439200D03*
X435300D03*
X431750D03*
X682250Y171830D03*
Y168230D03*
X682300Y165530D03*
Y161930D03*
X695450Y171850D03*
Y168250D03*
X701923Y165614D03*
Y162014D03*
X701944Y159243D03*
Y155643D03*
X701950Y152940D03*
Y149340D03*
X701952Y146565D03*
%LPD*%
G75*
G54D10*
G01X46194Y179835D02*
Y173772D01*
X54697Y165269D01*
G01X58697D02*
X50194Y173772D01*
Y179835D01*
G01X85795Y378426D02*
X81374D01*
X78400Y381400D01*
X68100D01*
X65500Y378800D01*
G01D02*
X60900D01*
X59000Y380700D01*
X45467D01*
X43000Y378233D01*
G01X22000Y378352D02*
X24748Y381100D01*
X35801D01*
X38668Y378233D01*
X43000D01*
G01X162522Y331774D02*
X128611D01*
G01D02*
X104974D01*
X102300Y329100D01*
G01X357546Y230354D02*
X335334D01*
X327140Y222160D01*
Y164550D01*
X308510Y145920D01*
Y129406D01*
X282004Y102900D01*
X188657D01*
X186054Y105503D01*
G01D02*
X182103D01*
X182100Y105500D01*
G01X200550Y111350D02*
X201980Y109920D01*
X201981D01*
X204818Y107083D01*
G01X162522Y331774D02*
X196651D01*
X217825Y310600D01*
X222000D01*
G01X204818Y107083D02*
X206710Y105191D01*
X280396D01*
X306310Y131105D01*
Y146832D01*
X324940Y165462D01*
Y223072D01*
X334467Y232599D01*
X360008D01*
X360710Y231897D01*
G01X261996Y365663D02*
X264577D01*
X268450Y369536D01*
Y379509D01*
X269742Y380801D01*
G01X257996Y365663D02*
X260780Y368447D01*
X264249D01*
X266050Y370248D01*
Y385047D01*
G01X255200Y375750D02*
X249781D01*
X248698Y374667D01*
Y372535D01*
G01X254300Y369500D02*
X250035D01*
X248698Y370837D01*
Y372535D01*
G01X256900Y380900D02*
Y377450D01*
X255200Y375750D01*
G01X299635Y292650D02*
X298300Y293985D01*
Y297650D01*
G01X270618Y385867D02*
Y381677D01*
X269742Y380801D01*
G01X263250Y423411D02*
X265479D01*
X269500Y419390D01*
Y389300D01*
X266050Y385850D01*
Y385047D01*
G01X327868Y290125D02*
X331124D01*
X335700Y294701D01*
Y297650D01*
G01X387572Y249860D02*
X398489D01*
X399751Y248598D01*
Y247219D01*
X400870Y246100D01*
X411436D01*
G01X384203Y255279D02*
X385561Y253921D01*
X407479D01*
X407500Y253900D01*
G01X387481Y258473D02*
X388114Y257840D01*
X419240D01*
X419300Y257900D01*
G01X448500Y424000D02*
Y403339D01*
X432095Y386934D01*
X431940D01*
X431840Y386834D01*
X390571D01*
X367450Y409955D01*
G01X452500Y423500D02*
Y404227D01*
X433007Y384734D01*
X432852D01*
X432752Y384634D01*
X389171D01*
X367350Y406455D01*
G01X393900Y226300D02*
Y228148D01*
X393701Y228347D01*
G01X396100Y226300D02*
X396200D01*
G01X391811Y245772D02*
X394102D01*
X394554Y246224D01*
X398557D01*
X399608Y245173D01*
Y226608D01*
X399400Y226400D01*
G01X397638Y224410D02*
X396200Y225848D01*
Y226300D01*
G01X399400Y226400D02*
X399300Y226300D01*
X396200D01*
G01X426200Y254000D02*
Y254903D01*
X425197Y255906D01*
G01X411400Y256100D02*
X409643D01*
X409449Y255906D01*
G01X417400Y254000D02*
Y255829D01*
X417323Y255906D01*
G01X407500Y256100D02*
X405706D01*
X405512Y255906D01*
G01X411436Y243900D02*
X409644D01*
X409449Y244095D01*
G01X423297Y260100D02*
X424940D01*
X425197Y259843D01*
G01X412000Y262900D02*
Y261229D01*
X413386Y259843D01*
G01D02*
X414500Y260957D01*
Y262900D01*
G01X426200Y257900D02*
Y256909D01*
X425197Y255906D01*
G01X397638Y251969D02*
X400731D01*
X401800Y250900D01*
X406800D01*
G01X417323Y267717D02*
X419929Y265111D01*
Y263835D01*
G01D02*
Y262541D01*
X419300Y261912D01*
Y260100D01*
G01X423429Y263835D02*
X421260Y261666D01*
Y259843D01*
G01X429339Y267240D02*
Y263986D01*
X429134Y263781D01*
G01X428400Y257900D02*
Y256640D01*
X429134Y255906D01*
G01X428400Y254000D02*
Y255172D01*
X429134Y255906D01*
G01X411436Y246100D02*
X418542D01*
X419433Y246991D01*
Y253833D01*
X419600Y254000D01*
G01X421260Y255906D02*
Y255660D01*
X419600Y254000D01*
G01X412000Y265100D02*
X409733D01*
X409000Y265833D01*
X396417D01*
X395006Y264422D01*
G01X414500Y265100D02*
X416000D01*
X417323Y263777D01*
Y259843D01*
G01X412000Y265100D02*
X414500D01*
G01X411379Y253921D02*
X411400Y253900D01*
G01X413386Y255906D02*
Y254886D01*
X412421Y253921D01*
X411379D01*
G01D02*
X407521D01*
X407500Y253900D01*
G01X419300Y257900D02*
X423297D01*
G01X429134Y251969D02*
X424454D01*
X423223Y253200D01*
Y257826D01*
X423297Y257900D01*
G01X415400Y312300D02*
Y309800D01*
X416891Y308309D01*
Y308060D01*
X417323Y307628D01*
Y307087D01*
G01X415400Y314500D02*
X416862D01*
X417323Y314961D01*
G01X489050Y210650D02*
Y211738D01*
X488189Y212599D01*
G01X491250Y210650D02*
Y211723D01*
X492126Y212599D01*
G01X488189Y240158D02*
X488150Y240197D01*
Y242150D01*
G01X488200Y246000D02*
X488189Y246011D01*
Y248032D01*
G01X488200Y250000D02*
X488189Y249989D01*
Y248032D01*
G01X488200Y253900D02*
X488189Y253911D01*
Y255906D01*
G01X488200Y257900D02*
X488189Y257911D01*
Y259843D01*
G01X488200Y261950D02*
X488189Y261939D01*
Y259843D01*
G01X492100Y265600D02*
X492126Y265626D01*
Y267717D01*
G01X488200Y269700D02*
X488190Y269710D01*
Y271653D01*
X488189Y271654D01*
G01X492126Y275591D02*
Y273676D01*
X492100Y273650D01*
G01X492150Y277500D02*
Y275615D01*
X492126Y275591D01*
G01X488050Y281500D02*
Y279667D01*
X488189Y279528D01*
G01X492126Y283465D02*
Y284917D01*
X492150Y284941D01*
Y285450D01*
G01X458700Y298100D02*
X457806D01*
X456693Y299213D01*
G01X458700Y300300D02*
Y302150D01*
X457700Y303150D01*
X456693D01*
G01X569989Y461261D02*
Y465238D01*
X570669Y465918D01*
G01D02*
X571651Y466900D01*
X574250D01*
G01X634050Y469200D02*
X631892Y471358D01*
X590308D01*
X588400Y469450D01*
G01X633676Y460080D02*
Y465774D01*
X630750Y468700D01*
X621308D01*
G01X617000D02*
X621308D01*
G01X627570Y452930D02*
X633850D01*
G01X639120Y452130D02*
X634650D01*
X633850Y452930D01*
G01X620600Y458500D02*
X626170Y452930D01*
X627570D01*
G01X577550Y487900D02*
X609768D01*
G01D02*
X633962D01*
X645970Y475892D01*
Y399130D01*
G01X697149Y219742D02*
Y216631D01*
X695253Y214735D01*
G01D02*
X692250Y211732D01*
Y210200D01*
G01X688250D02*
Y213542D01*
X689783Y215075D01*
G01D02*
X692949Y218241D01*
Y219742D01*
G01X666031Y380133D02*
Y383331D01*
X667400Y384700D01*
G01X669031Y388383D02*
Y386331D01*
X667400Y384700D01*
G01X661531Y380133D02*
Y384229D01*
X662029Y384727D01*
G01X665031Y388383D02*
Y387729D01*
X662029Y384727D01*
G01X657031Y384900D02*
Y380133D01*
G01X653360Y386210D02*
X656031D01*
X657031Y385210D01*
Y384900D01*
G01X680700Y378200D02*
X680600Y378100D01*
Y373863D01*
X680700Y373763D01*
G01D02*
Y366779D01*
G01X687150Y385550D02*
Y387635D01*
X685402Y389383D01*
X684017D01*
G01X675031D02*
X684017D01*
G01X672131Y386633D02*
X672281D01*
X675031Y389383D01*
G01X657031Y376633D02*
X651706D01*
X650530Y377809D01*
Y379699D01*
G01X653007Y382828D02*
X651678D01*
X650530Y381680D01*
Y379699D01*
G01X657031Y376633D02*
Y375469D01*
X658500Y374000D01*
Y372100D01*
G01X739680Y438140D02*
X742540D01*
X743480Y439080D01*
G01X740900Y456400D02*
X740371Y455871D01*
X733712D01*
X15812Y-86244D03*
X27058Y25484D03*
X81539Y542850D03*
X116063Y14567D03*
Y39075D03*
X98425Y472441D03*
X137795D03*
X374015Y156220D03*
X389764Y460630D03*
X437008D03*
X411652Y539991D03*
X531496Y371299D03*
X596456Y116142D03*
X812711Y-86834D03*
X798456Y26432D03*
X781496Y198818D03*
G54D20*
X37402Y499724D03*
X789370D03*
G54D11*
X15364Y5500D03*
X10364D03*
X5500Y10384D03*
Y15384D03*
Y20384D03*
Y25384D03*
Y30384D03*
Y35384D03*
Y40384D03*
Y45384D03*
Y50384D03*
Y55384D03*
Y60384D03*
Y65384D03*
Y70384D03*
Y75384D03*
Y80384D03*
Y85384D03*
Y90384D03*
Y95384D03*
Y100384D03*
Y105384D03*
Y110384D03*
Y115384D03*
Y120384D03*
Y125384D03*
Y130384D03*
Y135384D03*
Y140384D03*
Y145384D03*
Y150384D03*
Y155384D03*
Y160384D03*
Y165384D03*
Y170384D03*
Y175384D03*
Y180384D03*
Y185384D03*
Y190384D03*
Y195384D03*
Y200384D03*
Y205384D03*
Y210384D03*
Y215384D03*
Y220384D03*
Y225384D03*
Y230384D03*
Y235384D03*
Y240384D03*
Y245384D03*
Y250384D03*
Y255384D03*
Y260384D03*
Y265384D03*
Y270384D03*
Y275384D03*
Y280384D03*
Y285384D03*
Y290384D03*
Y295384D03*
Y300384D03*
Y305384D03*
Y310384D03*
Y315384D03*
Y320384D03*
Y325384D03*
Y330384D03*
Y335384D03*
Y340384D03*
Y345384D03*
Y350384D03*
Y355384D03*
Y360384D03*
Y365384D03*
Y370384D03*
Y375384D03*
Y380384D03*
Y385384D03*
Y390384D03*
Y395384D03*
Y400384D03*
Y405384D03*
Y410384D03*
Y415384D03*
Y420384D03*
Y425384D03*
Y430384D03*
Y435384D03*
Y440384D03*
Y445384D03*
Y450384D03*
Y455384D03*
Y460384D03*
Y465384D03*
Y470384D03*
Y475384D03*
Y480384D03*
Y485384D03*
Y530384D03*
Y525384D03*
Y520384D03*
Y515384D03*
Y510384D03*
Y505384D03*
Y490384D03*
Y495384D03*
Y500384D03*
Y535384D03*
Y540384D03*
Y545384D03*
Y550384D03*
Y555384D03*
Y560384D03*
X10266Y565366D03*
X15266D03*
X75364Y5500D03*
X70364D03*
X65364D03*
X60364D03*
X55364D03*
X50364D03*
X45364D03*
X40364D03*
X35364D03*
X30364D03*
X25364D03*
X20364D03*
X75119Y111166D03*
X20266Y565366D03*
X25266D03*
X30266D03*
X35266D03*
X40266D03*
X45266D03*
X50266D03*
X55266D03*
X60266D03*
X65266D03*
X70266D03*
X75266D03*
X95364Y5500D03*
X90364D03*
X85364D03*
X80364D03*
X105619Y111166D03*
X81119D03*
X87619D03*
X93619D03*
X99619D03*
X128580Y170810D03*
X122984Y170984D03*
X123200Y175800D03*
X125741Y166309D03*
X128459Y175658D03*
X140000Y204950D03*
X94080Y448470D03*
X80266Y565366D03*
X85266D03*
X90266D03*
X95266D03*
X100266D03*
X105266D03*
X110266D03*
X115266D03*
X120266D03*
X125266D03*
X130266D03*
X135266D03*
X200364Y5500D03*
X195364D03*
X190364D03*
X185364D03*
X180364D03*
X175364D03*
X170364D03*
X192830Y170500D03*
X197630D03*
X192830Y165700D03*
X197630D03*
X192830Y160900D03*
X197630D03*
X170900Y160500D03*
X151500D03*
X156300D03*
X161100D03*
X165900D03*
X198557Y153196D03*
X191900Y196100D03*
X196900D03*
X201700D03*
X196900Y200900D03*
X191900D03*
X196900Y205700D03*
X191900D03*
X196900Y210500D03*
X191900D03*
X201700Y205700D03*
Y200900D03*
X151500Y205000D03*
X156300D03*
X161100D03*
X165900D03*
X170900D03*
X178450Y203150D03*
X144800Y204950D03*
X177850Y324800D03*
X174995Y353588D03*
Y358388D03*
X165195D03*
X169995D03*
Y353588D03*
X197718Y350937D03*
Y355859D03*
X157650Y418100D03*
X160400Y422900D03*
X160550Y414100D03*
X177468Y417900D03*
X142865Y424021D03*
X143608Y415900D03*
X158067Y378857D03*
X160400Y427700D03*
Y432500D03*
X176311Y445493D03*
X176423Y440472D03*
X177421Y432909D03*
X177532Y426134D03*
X145392Y445207D03*
X145456Y440338D03*
X142991Y430900D03*
X200266Y565366D03*
X195266D03*
X190266D03*
X185266D03*
X180266D03*
X175266D03*
X140266D03*
X145266D03*
X150266D03*
X155266D03*
X160266D03*
X165266D03*
X170266D03*
X260364Y5500D03*
X255364D03*
X250364D03*
X245364D03*
X240364D03*
X235364D03*
X230364D03*
X225364D03*
X220364D03*
X215364D03*
X210364D03*
X205364D03*
X222700Y149300D03*
X227500D03*
X222700Y144500D03*
X227500D03*
X222700Y139700D03*
X227500D03*
X222700Y158900D03*
X227500D03*
X222700Y154100D03*
X227500D03*
X202430Y170500D03*
Y165700D03*
Y160900D03*
X253600Y139500D03*
Y134700D03*
X251800Y153600D03*
Y144000D03*
Y148800D03*
X258400Y134700D03*
Y139500D03*
X263200Y134700D03*
Y139500D03*
X222800Y204600D03*
X227600D03*
X222800Y219000D03*
X227600D03*
X222800Y214200D03*
X227600D03*
X222800Y209400D03*
X227600D03*
X222490Y235373D03*
X227290D03*
X222246Y229952D03*
X227046D03*
X222800Y223800D03*
X227600D03*
X253600Y230500D03*
Y225700D03*
Y220900D03*
X258400Y230500D03*
Y225700D03*
Y220900D03*
X263200Y230500D03*
Y225700D03*
Y220900D03*
X222460Y240264D03*
X227260D03*
X249204Y244103D03*
X254300Y357732D03*
X222818Y364806D03*
X222909Y371864D03*
X223000Y378246D03*
X246700Y418600D03*
X209052Y470198D03*
X213700Y448450D03*
X208900D03*
X203000Y451300D03*
X204252Y470198D03*
X204364Y478917D03*
X209164D03*
X212589Y494694D03*
X220589D03*
X216589Y489694D03*
X208589D03*
X224589D03*
X205266Y565366D03*
X210266D03*
X215266D03*
X220266D03*
X225266D03*
X230266D03*
X235266D03*
X240266D03*
X245266D03*
X250266D03*
X255266D03*
X260266D03*
X325364Y5500D03*
X320364D03*
X315364D03*
X310364D03*
X305364D03*
X300364D03*
X295364D03*
X290364D03*
X285364D03*
X280364D03*
X275364D03*
X270364D03*
X265364D03*
X295960Y148987D03*
Y154387D03*
X308907Y171800D03*
Y166400D03*
Y161000D03*
X287000Y117600D03*
Y125000D03*
X285500Y130400D03*
X290300D03*
X287300Y173000D03*
X292100D03*
X295650Y169554D03*
X295100Y130400D03*
X272800Y168000D03*
Y172800D03*
Y134700D03*
X268000Y165962D03*
X268064Y171792D03*
X268000Y158700D03*
Y153900D03*
Y134700D03*
Y139500D03*
Y144300D03*
Y149100D03*
X296200Y195900D03*
Y190500D03*
X308907Y215200D03*
Y220600D03*
Y226000D03*
Y231400D03*
Y236800D03*
Y209800D03*
Y188200D03*
Y199000D03*
Y204400D03*
Y177200D03*
Y193600D03*
Y182800D03*
X296400Y237950D03*
Y232550D03*
X295801Y210294D03*
X292600Y214500D03*
X287800D03*
X272800Y177600D03*
X268064Y184062D03*
X268000Y235300D03*
Y230500D03*
Y225700D03*
Y220900D03*
Y216000D03*
Y211200D03*
X268118Y191305D03*
X268000Y206400D03*
Y196800D03*
Y201600D03*
Y178062D03*
X308907Y242200D03*
X295879Y255540D03*
X291079D03*
X286279D03*
X266404Y249707D03*
X268000Y244900D03*
Y240100D03*
X276070Y395357D03*
X265266Y565366D03*
X270266D03*
X275266D03*
X280266D03*
X285266D03*
X290266D03*
X295266D03*
X300266D03*
X305266D03*
X310266D03*
X315266D03*
X320266D03*
X325266D03*
X330364Y5500D03*
X346700Y296333D03*
Y291533D03*
X371648Y335023D03*
X350586Y495815D03*
X355523Y495025D03*
X360461Y494236D03*
X365398Y493446D03*
X370335Y492656D03*
X375272Y491866D03*
X380210Y491077D03*
X385169Y490563D03*
X329156Y545492D03*
Y540492D03*
Y535492D03*
Y530492D03*
Y525492D03*
Y520492D03*
Y515492D03*
Y560492D03*
Y555492D03*
Y550492D03*
X427166Y297245D03*
X431102Y293307D03*
X442908Y293298D03*
X419292Y297245D03*
X423221Y293300D03*
X423228Y305118D03*
X431102Y301181D03*
X423229Y320867D03*
X431105Y309010D03*
X419291Y309055D03*
X442913Y305118D03*
X438976Y301181D03*
Y309055D03*
X434000Y322200D03*
X405169Y490563D03*
X410169D03*
X415169D03*
X420169D03*
X425169D03*
X430169D03*
X435169D03*
X440169D03*
X445146Y490850D03*
X450083Y491640D03*
X390169Y490563D03*
X395169D03*
X400169D03*
X503468Y324325D03*
X497550Y324150D03*
X496000Y336000D03*
X506700Y336200D03*
X501400Y336000D03*
X468500Y333500D03*
X472600Y310400D03*
X466535Y305118D03*
X505500Y464400D03*
Y469200D03*
Y474000D03*
X509500Y450800D03*
Y446000D03*
Y441200D03*
X469832Y494799D03*
X474769Y495589D03*
X455020Y492430D03*
X459958Y493219D03*
X464895Y494009D03*
X497636Y515532D03*
Y520532D03*
Y525532D03*
Y530532D03*
Y535532D03*
Y540532D03*
Y545532D03*
Y550532D03*
Y555532D03*
Y560532D03*
X502550Y565366D03*
X507550D03*
X512550D03*
X570234Y298026D03*
X572634Y293526D03*
X557500Y343350D03*
X552100Y343300D03*
X524500Y335500D03*
X516194Y332572D03*
X571300Y414800D03*
X567200Y407700D03*
X572062Y384378D03*
X527742Y425481D03*
X522942D03*
X518142D03*
X527742Y432481D03*
X522942D03*
X518142D03*
X529500Y471500D03*
X551400Y437800D03*
X545900D03*
X539800Y437900D03*
X517550Y565366D03*
X522550D03*
X527550D03*
X532550D03*
X537550D03*
X542550D03*
X547550D03*
X552550D03*
X557550D03*
X562550D03*
X567550D03*
X572550D03*
X591446Y6545D03*
X596446D03*
X601446D03*
X606446D03*
X611446D03*
X616446D03*
X621446D03*
X636446D03*
X631446D03*
X626446D03*
X576797Y113877D03*
X582554Y116361D03*
X631700Y198500D03*
X626400D03*
X575134Y298026D03*
X577534Y293526D03*
X580034Y298026D03*
X580900Y414800D03*
X576100D03*
X632150Y389100D03*
X576862Y384378D03*
X581087Y379569D03*
X576287D03*
X581692Y384378D03*
X628113Y428617D03*
X623313D03*
X618513D03*
X613713D03*
X605534Y480027D03*
X635000Y427784D03*
X619600Y446100D03*
X629200D03*
X624400D03*
X577550Y565366D03*
X582550D03*
X587550D03*
X592550D03*
X597550D03*
X602550D03*
X607550D03*
X612550D03*
X617550D03*
X622550D03*
X627550D03*
X632550D03*
X641446Y6545D03*
X646446D03*
X651446D03*
X696446D03*
X691446D03*
X661446D03*
X656446D03*
X686446D03*
X681446D03*
X676446D03*
X671446D03*
X666446D03*
X655964Y52248D03*
X650936Y160874D03*
X656878Y161079D03*
X695770Y125429D03*
X693674Y132295D03*
X648035Y154330D03*
X642300Y198500D03*
X637000D03*
X646004Y179768D03*
X650722Y183439D03*
X646000Y185900D03*
X694087Y201724D03*
X690207Y205597D03*
X657113Y198415D03*
X651722Y198588D03*
X675136Y268500D03*
X637705Y298765D03*
X642705D03*
X659977Y323082D03*
X664731Y324099D03*
X660115Y351977D03*
Y356777D03*
X664731Y343299D03*
X655500Y360000D03*
X660115Y361577D03*
X664731Y338499D03*
Y333699D03*
Y328899D03*
X659977Y342282D03*
Y332682D03*
Y347082D03*
Y337482D03*
Y327882D03*
X696900Y337800D03*
X697500Y358200D03*
X637705Y303765D03*
X642705D03*
X674700Y306300D03*
X679500D03*
Y311100D03*
X674700D03*
X679500Y315900D03*
X674700D03*
X665520Y307707D03*
Y312507D03*
X654642D03*
X654488Y317417D03*
X660100Y307500D03*
X654642Y307707D03*
X665478Y317527D03*
X684400Y400100D03*
X637550Y389050D03*
X655532Y425245D03*
X658032Y420245D03*
X653032D03*
X653200Y408800D03*
X694950Y477850D03*
Y473050D03*
X688500Y484400D03*
X675700Y468000D03*
Y463500D03*
X675400Y472300D03*
X659000Y428900D03*
X652200Y429100D03*
X639120Y462230D03*
X688500Y488600D03*
X637550Y565366D03*
X642550D03*
X647550D03*
X652550D03*
X657550D03*
X662550D03*
X667550D03*
X672550D03*
X677550D03*
X682550D03*
X687550D03*
X692550D03*
X697550D03*
X701446Y6545D03*
X734500Y113400D03*
X737100Y103000D03*
X730200Y98200D03*
X719500Y102900D03*
X742700Y103100D03*
X739900Y112500D03*
X745700Y108700D03*
X724200Y110700D03*
X719000Y112700D03*
X715100Y107300D03*
X708300Y113300D03*
X725600Y103600D03*
X713700Y112500D03*
X724600Y97100D03*
X717087Y97384D03*
X703600Y110600D03*
X729400Y111800D03*
X734500Y139200D03*
X743400Y139100D03*
X738000Y133900D03*
X746400Y134600D03*
X736730Y166522D03*
X733372Y130235D03*
X742700Y130600D03*
X736800Y125200D03*
X733600Y120500D03*
X738200Y117600D03*
X741500Y146500D03*
X747700Y114800D03*
X747200Y127400D03*
X744222Y120527D03*
X716040Y176322D03*
X699999Y132427D03*
X727700Y118000D03*
X707861Y133930D03*
X752500Y127500D03*
X733792Y175376D03*
X733500Y146000D03*
X721500Y202600D03*
X710687Y202564D03*
X726032Y205904D03*
X736078Y181764D03*
X745659Y183788D03*
X746691Y189552D03*
X734043Y187231D03*
X745778Y178204D03*
X742978Y206202D03*
X715300Y214400D03*
X742200Y340800D03*
Y345600D03*
X737400Y340800D03*
Y345600D03*
X732600Y331200D03*
Y336000D03*
Y340800D03*
Y355200D03*
Y350400D03*
Y345600D03*
X701100Y315900D03*
X705900D03*
X701100Y311100D03*
X705900D03*
Y306300D03*
X701100D03*
X714600Y338900D03*
Y348500D03*
Y343700D03*
X709800Y348500D03*
Y343700D03*
X706500Y337800D03*
X701700D03*
X707100Y358200D03*
X702300D03*
X704115Y414466D03*
Y409666D03*
Y404866D03*
Y400066D03*
X722100Y368300D03*
X717300D03*
X712500D03*
X742200Y380400D03*
Y370800D03*
Y375600D03*
X728700Y381000D03*
Y376200D03*
Y371400D03*
X722100Y363500D03*
X717300D03*
X712500D03*
X705900Y386900D03*
X711000Y395100D03*
X710900Y386800D03*
X706000Y395100D03*
X725247Y458974D03*
X724422Y464139D03*
X724400Y485200D03*
Y480400D03*
Y475600D03*
X740900Y476400D03*
Y469400D03*
Y461900D03*
X704340Y468062D03*
X705400Y477400D03*
X724400Y490200D03*
X702550Y565366D03*
X707550D03*
X712550D03*
X717550D03*
X722550D03*
X727550D03*
X732550D03*
X737550D03*
X742550D03*
X747550D03*
X752550D03*
X757550D03*
X821272Y49340D03*
Y44340D03*
Y39340D03*
Y34340D03*
Y29340D03*
Y24340D03*
Y19340D03*
Y14340D03*
Y9340D03*
X815364Y5500D03*
X810364D03*
X805364D03*
X800364D03*
X795364D03*
X790364D03*
X785364D03*
X780364D03*
X775364D03*
X770364D03*
X765364D03*
X821272Y114340D03*
Y109340D03*
Y104340D03*
Y99340D03*
Y94340D03*
Y89340D03*
Y84340D03*
Y79340D03*
Y74340D03*
Y69340D03*
Y64340D03*
Y59340D03*
Y54340D03*
Y174340D03*
Y169340D03*
Y164340D03*
Y159340D03*
Y154340D03*
Y149340D03*
Y144340D03*
Y139340D03*
Y134340D03*
Y129340D03*
Y124340D03*
Y119340D03*
Y234340D03*
Y229340D03*
Y224340D03*
Y219340D03*
Y214340D03*
Y209340D03*
Y204340D03*
Y199340D03*
Y194340D03*
Y189340D03*
Y184340D03*
Y179340D03*
X771083Y211784D03*
X821272Y299340D03*
Y294340D03*
Y289340D03*
Y284340D03*
Y279340D03*
Y274340D03*
Y269340D03*
Y264340D03*
Y259340D03*
Y254340D03*
Y249340D03*
Y244340D03*
Y239340D03*
Y359340D03*
Y354340D03*
Y349340D03*
Y344340D03*
Y339340D03*
Y334340D03*
Y329340D03*
Y324340D03*
Y319340D03*
Y314340D03*
Y309340D03*
Y304340D03*
Y424340D03*
Y419340D03*
Y414340D03*
Y409340D03*
Y404340D03*
Y399340D03*
Y394340D03*
Y389340D03*
Y384340D03*
Y379340D03*
Y374340D03*
Y369340D03*
Y364340D03*
Y484340D03*
Y479340D03*
Y474340D03*
Y469340D03*
Y464340D03*
Y459340D03*
Y454340D03*
Y449340D03*
Y444340D03*
Y439340D03*
Y434340D03*
Y429340D03*
Y504340D03*
Y509340D03*
Y514340D03*
Y519340D03*
Y524340D03*
Y529340D03*
Y549340D03*
Y544340D03*
Y539340D03*
Y534340D03*
Y499340D03*
Y494340D03*
Y489340D03*
X762550Y565366D03*
X767550D03*
X772550D03*
X777550D03*
X782550D03*
X787550D03*
X792550D03*
X797550D03*
X802550D03*
X807550D03*
X812550D03*
X817550D03*
X821272Y559340D03*
Y554340D03*
G54D21*
X37402Y535158D03*
X789370D03*
G54D12*
G01X312741Y279840D02*
X311072Y278171D01*
G01D02*
X283161D01*
X280332Y281000D01*
X268400D01*
G01X645024Y52503D02*
X640718Y56809D01*
X621323D01*
X582554Y95578D01*
Y116361D01*
G01X633000Y71421D02*
Y74527D01*
X611300Y96227D01*
Y205650D01*
X622400Y216750D01*
X37700Y64400D03*
X86150Y441700D03*
X737400Y485700D03*
G54D30*
X162038Y454386D03*
G54D31*
X254800Y415000D03*
X316100Y290100D03*
X342200Y285800D03*
Y277770D03*
X380771Y332810D03*
X476300Y270600D03*
X476200Y262500D03*
X476500Y249200D03*
X476400Y254800D03*
X557800Y461260D03*
X520200Y456800D03*
X608526Y234952D03*
X651254Y138591D03*
X650317Y116114D03*
Y119614D03*
X676752Y150915D03*
Y154415D03*
X686202Y145315D03*
X686200Y151100D03*
X686100Y157350D03*
X664200Y128650D03*
X644200Y238400D03*
X721933Y195408D03*
X707262Y195365D03*
X699652Y194895D03*
G54D22*
X134500Y390500D03*
G54D40*
X275200Y141000D03*
X274700Y163000D03*
X275200Y204500D03*
Y224500D03*
X274700Y183000D03*
Y246000D03*
X618726Y252452D03*
X653700Y252000D03*
X720304Y338538D03*
G54D13*
G01X-34018Y-300855D02*
G02I-12000J0D01*
G01X-39168D02*
G02I-6850J0D01*
G01X-30018D02*
X-62018D01*
G01X-30018Y-316855D02*
Y-396855D01*
G01D02*
X1320682D01*
G01X-30018Y-352355D02*
X1320682D01*
G01X-46018Y-316855D02*
Y-284855D01*
G01X-30018Y-316855D02*
X1320682D01*
G01X59600Y152000D02*
Y156412D01*
X34567Y181445D01*
Y205090D01*
G01X45000Y202200D02*
X40267D01*
X39301Y203166D01*
G01X34567Y205090D02*
Y209070D01*
X39320Y213823D01*
G01X78800Y205900D02*
X78620Y206080D01*
Y210280D01*
X82240Y213900D01*
X92300D01*
G01Y194900D02*
X83581D01*
X78800Y199681D01*
Y205900D01*
G01X158612Y126645D02*
Y121245D01*
X160057Y119800D01*
X170652D01*
G01X198202Y135298D02*
Y132698D01*
X185304Y119800D01*
X170652D01*
G01X253552Y130871D02*
X244311Y121630D01*
X201139D01*
G01X177400Y149700D02*
Y145601D01*
X172800Y141001D01*
G01X180300Y175400D02*
Y153400D01*
X177400Y150500D01*
Y149700D01*
G01X261499Y55353D02*
X261762Y55616D01*
Y59618D01*
G01X254300Y357732D02*
Y363500D01*
G01X255500Y423361D02*
X261639Y429500D01*
X270734D01*
X276070Y424164D01*
Y401100D01*
G01X261581Y370979D02*
X262800Y372198D01*
Y375750D01*
G01X256172Y409530D02*
Y407306D01*
X257516Y405962D01*
X259132D01*
G01X262600Y410900D02*
Y407339D01*
X261223Y405962D01*
X259132D01*
G01X262600Y416900D02*
X256650D01*
X254750Y415000D01*
G01X281700Y59068D02*
X278514D01*
X277514Y58068D01*
G01X285500Y59068D02*
X288161D01*
X289161Y58068D01*
G01X265262Y59618D02*
Y57118D01*
X267188Y55192D01*
G01X281700Y52285D02*
Y55568D01*
G01X285500Y52285D02*
Y55568D01*
G01X312550Y290100D02*
X310000Y292650D01*
X299635D01*
G01X287500Y289750D02*
Y296974D01*
X284498Y299976D01*
G01X280800Y325000D02*
Y291950D01*
X283000Y289750D01*
G01X280217Y350927D02*
Y378250D01*
X291959Y389992D01*
X298152D01*
G01X276070Y395357D02*
Y401100D01*
G01X298152Y389992D02*
X316786D01*
G01X338650Y285800D02*
Y281350D01*
G01D02*
Y277770D01*
G01X342150Y289600D02*
Y285800D01*
G01X367368Y264441D02*
X365416D01*
X364216Y263241D01*
X362868D01*
G01X358169Y265318D02*
X355731D01*
X352254Y261841D01*
G01X358169Y265318D02*
X359297D01*
X361374Y263241D01*
X362868D01*
G01X383677Y252037D02*
X379233Y256481D01*
Y263025D01*
X377817Y264441D01*
X367368D01*
G01X383677Y252037D02*
X385854Y249860D01*
X387572D01*
G01X391839Y263634D02*
X389366D01*
X387453Y265547D01*
Y300157D01*
X380474Y307136D01*
X372642D01*
X369616Y310162D01*
X367177D01*
G01X367368Y282087D02*
X377519D01*
X379700Y279906D01*
G01X362868Y283287D02*
X361618Y282037D01*
X358342D01*
G01D02*
X356892Y283487D01*
X352228D01*
G01X367368Y282087D02*
X365813D01*
X364613Y283287D01*
X362868D01*
G01X379700Y279906D02*
X382000Y277606D01*
Y257482D01*
X384203Y255279D01*
G01X385803Y260151D02*
X384559Y261395D01*
Y279573D01*
X378566Y285566D01*
X371434D01*
X369889Y287111D01*
Y292641D01*
G01X385803Y260151D02*
X387481Y258473D01*
G01X362689Y291341D02*
X362159D01*
X360909Y292591D01*
X358222D01*
G01D02*
X355572Y289941D01*
X352222D01*
G01X369889Y292641D02*
X364500D01*
X363200Y291341D01*
X362689D01*
G01X389709Y245772D02*
X385377D01*
X377286Y253863D01*
X367417D01*
X367340Y253940D01*
G01X352230Y255371D02*
X356821D01*
X358298Y253894D01*
G01X367340Y253940D02*
X364010D01*
X362810Y255140D01*
G01D02*
X359544D01*
X358298Y253894D01*
G01X348600Y323900D02*
X353110D01*
X354800Y322210D01*
Y319900D01*
G01X377221Y332810D02*
Y333601D01*
X379148Y335528D01*
Y337184D01*
G01X375148D02*
Y341070D01*
G01X382600Y337200D02*
Y334689D01*
X380721Y332810D01*
G01X377633Y314895D02*
X375539D01*
X374432Y316002D01*
G01X358550Y330500D02*
Y333450D01*
X356550Y335450D01*
Y337200D01*
G01X362677Y311062D02*
X360500D01*
X359550Y310112D01*
X358214D01*
G01D02*
X355388D01*
X353938Y311562D01*
X352214D01*
G01X367177Y310162D02*
X365900D01*
X365000Y311062D01*
X362677D01*
G01X389709Y245772D02*
X391811D01*
G01X399208Y262952D02*
X397638Y261382D01*
Y259843D01*
G01X395006Y264422D02*
X394218Y263634D01*
X391839D01*
G01X427500Y334150D02*
Y337500D01*
G01X421500Y334250D02*
Y337500D01*
G01X409500Y330250D02*
Y326823D01*
X409449Y326772D01*
G01X427500Y337500D02*
Y340550D01*
G01X421500Y337500D02*
Y341050D01*
G01X398180Y331430D02*
Y327314D01*
X397638Y326772D01*
G01X411470Y335630D02*
Y334000D01*
X409500Y332030D01*
Y330250D01*
G01X440236Y351341D02*
X444247D01*
X444959Y352053D01*
G01X391900Y340650D02*
X389559Y338309D01*
Y337103D01*
G01X416822Y347133D02*
X417400Y346555D01*
Y344050D01*
G01X412381Y347149D02*
X411013D01*
X409100Y345236D01*
Y344050D01*
G01X412381Y347149D02*
X413400Y346130D01*
Y344050D01*
G01X449400Y334250D02*
X445400D01*
G01X440740Y344694D02*
Y347540D01*
X441000Y347800D01*
G01D02*
X445000D01*
X447300Y345500D01*
Y344350D01*
G01X433500Y337500D02*
X433195Y337805D01*
Y340555D01*
X432900Y340850D01*
G01X435200Y334050D02*
Y335800D01*
X433500Y337500D01*
G01X397000Y337000D02*
Y339650D01*
X396000Y340650D01*
G01X469490Y295572D02*
X472145D01*
X472441Y295276D01*
G01X464567Y299214D02*
X465640Y298141D01*
Y295572D01*
G01X492132Y296773D02*
X490629D01*
X488189Y299213D01*
G01X465640Y291972D02*
X463936D01*
X460631Y295277D01*
G01X468505Y287402D02*
X469490Y288387D01*
G01D02*
Y291972D01*
G01X491445Y350408D02*
Y353522D01*
X490094Y354873D01*
G01X460000Y344250D02*
X464000D01*
G01D02*
X464500Y344750D01*
Y347410D01*
G01X492132Y300373D02*
Y303144D01*
X492126Y303150D01*
G01X472000Y354250D02*
Y357925D01*
X467774Y362151D01*
G01X490094Y354873D02*
X490000Y354967D01*
Y363700D01*
G01X482618Y342892D02*
Y346468D01*
X481359Y347727D01*
G01X481850Y363400D02*
Y360439D01*
X483094Y359195D01*
G01X477400Y350850D02*
Y348550D01*
X476500Y347650D01*
G01X478618Y342892D02*
Y345532D01*
X476500Y347650D01*
G01X474577Y342915D02*
X478595D01*
X478618Y342892D01*
G01X493200Y358800D02*
X495303D01*
X496100Y358003D01*
Y355350D01*
G01X481850Y367500D02*
X484400D01*
X485100Y366800D01*
G01X502200Y364059D02*
Y365500D01*
X502850Y366150D01*
Y368500D01*
G01D02*
X502700Y368350D01*
X498550D01*
G01X478250Y371800D02*
X473900D01*
G01X485100Y363400D02*
X481850D01*
G01X533182Y-316855D02*
Y-396855D01*
G01X549200Y354850D02*
Y356022D01*
X547225Y357997D01*
G01X545200Y354850D02*
Y355972D01*
X547225Y357997D01*
G01X547908Y335182D02*
X547379Y335711D01*
Y338352D01*
G01X541747Y335215D02*
X539900Y337062D01*
Y338300D01*
G01X529947Y335250D02*
Y336147D01*
X532200Y338400D01*
X534000D01*
G01X533947Y335250D02*
X529947D01*
G01X540200Y354850D02*
Y356022D01*
X538225Y357997D01*
G01X536200Y354850D02*
Y355972D01*
X538225Y357997D01*
G01X558000Y351750D02*
Y354262D01*
X555697Y356565D01*
G01X554000Y351750D02*
Y354868D01*
X555697Y356565D01*
G01X584280Y424030D02*
X563764D01*
X561434Y421700D01*
X517000D01*
X514405Y424295D01*
Y435053D01*
X520150Y440798D01*
Y456800D01*
G01X603650Y315500D02*
X597891D01*
X594582Y318809D01*
Y331882D01*
X607200Y344500D01*
Y366800D01*
X609900Y369500D01*
Y404500D01*
X606700Y407700D01*
X572204D01*
G01X567200D02*
X572204D01*
G01X563050Y481025D02*
X557411D01*
G01X554250Y461260D02*
Y457500D01*
G01X574083Y476488D02*
Y479215D01*
X574667Y479799D01*
G01X549400Y485940D02*
X545880D01*
G01X542245Y480090D02*
X539040D01*
G01X521950Y488975D02*
X517125D01*
G01X633000Y65750D02*
Y71421D01*
G01X618773Y232097D02*
X624570Y226300D01*
X646172D01*
X651972Y220500D01*
X652000D01*
G01X609684Y231139D02*
Y229091D01*
X616728Y222047D01*
X645755D01*
X657002Y210800D01*
X662700D01*
X663405Y210095D01*
X668153D01*
G01X574667Y479799D02*
X577550Y482682D01*
Y483400D01*
G01X588663Y460037D02*
Y462337D01*
X587250Y463750D01*
G01X581500Y465000D02*
X586000D01*
X587250Y463750D01*
G01X585420Y456480D02*
X585250Y456310D01*
Y449500D01*
G01X581750D02*
X578840D01*
X577390Y450950D01*
Y453170D01*
G01D02*
Y456320D01*
X580070Y459000D01*
X581500D01*
G01X670682Y-316855D02*
Y-396855D01*
G01X663695Y23414D02*
X663698Y23411D01*
X667149D01*
G01X637003Y65759D02*
Y68809D01*
G01X644500Y65759D02*
X641003D01*
G01X651430Y174234D02*
X653573Y176377D01*
X654330D01*
G01X680132Y128735D02*
X679528Y128131D01*
Y125985D01*
G01X687750Y128700D02*
X691729D01*
X692148Y129119D01*
G01X641750Y166000D02*
X640908D01*
X639108Y167800D01*
G01X654263Y166929D02*
X651181D01*
G01X651430Y170634D02*
X651181Y170385D01*
Y166929D01*
G01X651204Y138591D02*
Y141709D01*
X651181Y141732D01*
G01X676632Y128735D02*
X676378Y128481D01*
Y125985D01*
G01X684250Y128700D02*
X682678Y127128D01*
Y125985D01*
G01X664150Y128650D02*
Y126355D01*
X663780Y125985D01*
G01X689132Y199845D02*
X687452Y201525D01*
Y201574D01*
X685826D01*
G01X695750Y210200D02*
Y208476D01*
X697069Y207157D01*
G01X683913Y213313D02*
X676494Y220732D01*
X676268D01*
X675900Y221100D01*
X661544D01*
X656427Y226217D01*
G01X651400Y233700D02*
Y231244D01*
X656427Y226217D01*
G01X684750Y210200D02*
Y208802D01*
X686352Y207200D01*
G01X663779Y192125D02*
X663462Y192442D01*
Y195705D01*
G01X671142Y195715D02*
Y193189D01*
X670078Y192125D01*
G01X674023Y213815D02*
X658685D01*
X652000Y220500D01*
G01X674172Y210095D02*
X668153D01*
G01X679400Y213300D02*
X675168Y217532D01*
X660236D01*
X650904Y226864D01*
G01D02*
X644300Y233468D01*
G01D02*
Y234700D01*
G01X691375Y282250D02*
X695625D01*
G01X669125Y274750D02*
Y280405D01*
G01X678739Y255684D02*
Y262854D01*
G01D02*
X674841D01*
G01X689468Y246655D02*
Y242922D01*
X686900Y240354D01*
G01X678739Y268500D02*
X675136D01*
G01X669450Y288000D02*
Y284900D01*
G01X700056Y371488D02*
X693800Y377744D01*
Y390700D01*
X684400Y400100D01*
G01X692200Y428700D02*
X686262Y422762D01*
X681532D01*
X674150Y415380D01*
G01X661531Y376633D02*
X657031D01*
G01X666031D02*
X661531D01*
G01X692200Y428700D02*
X699160Y435660D01*
X730670D01*
X745410Y450400D01*
Y457390D01*
X740900Y461900D01*
G01X639120Y458130D02*
Y462230D01*
G01X757650Y99605D02*
X754148D01*
X752853Y100900D01*
G01X738550Y97900D02*
X744700D01*
X745100Y97500D01*
G01X740329Y151899D02*
X743368D01*
X743452Y151815D01*
G01X737702Y160315D02*
X740427D01*
X740952Y159790D01*
X741077D01*
G01D02*
X740329Y159042D01*
Y155899D01*
G01X713500Y138700D02*
X717500D01*
G01X757471Y148193D02*
Y145050D01*
G01X757250Y169500D02*
X760750D01*
X760800Y169550D01*
G01X757750Y160800D02*
X760650D01*
X761400Y160050D01*
G01X714620Y221041D02*
X718249D01*
X719700Y219590D01*
Y218050D01*
G01X714620Y221041D02*
X711800D01*
X710800Y220041D01*
Y218050D01*
G01X792000Y229250D02*
X746110D01*
X743460Y231900D01*
G01X712596Y276558D02*
X707574D01*
G01X785682Y-316855D02*
Y-396855D01*
G01X772125Y78250D02*
Y83037D01*
X772116Y83046D01*
X772107D01*
G01X799493Y93250D02*
X795625D01*
G01X799250Y74625D02*
Y71125D01*
G01X782500Y137350D02*
Y134283D01*
G01X785000Y152000D02*
Y158900D01*
G01X794500Y134283D02*
Y137350D01*
G01D02*
X798500D01*
G01X790500D02*
X786500D01*
G01D02*
Y134283D01*
G01X760565Y140433D02*
X763533D01*
X764600Y141500D01*
G01X760565Y136383D02*
X764567D01*
X765200Y135750D01*
G01X760565Y136383D02*
Y132181D01*
G01X790000Y224700D02*
X794700D01*
X796500Y226500D01*
Y229250D01*
G01X805254Y263886D02*
X806000Y263140D01*
Y229100D01*
X793900Y217000D01*
X776299D01*
X771083Y211784D01*
G01X953182Y-316855D02*
Y-396855D01*
G01X1123182Y-316855D02*
Y-396855D01*
G01X1320682Y-316855D02*
Y-396855D01*
G01X1348682Y-300855D02*
G02I-12000J0D01*
G01X1343532D02*
G02I-6850J0D01*
G01X1336682Y-316855D02*
Y-284855D01*
G01X1352682Y-300855D02*
X1320682D01*
X22550Y156750D03*
X54697Y165269D03*
X58697D03*
X59600Y152000D03*
X71200Y137200D03*
X52400Y237800D03*
X28455Y187767D03*
X28749Y191548D03*
X39301Y203166D03*
X33700Y230600D03*
X21910Y217500D03*
X22250Y223500D03*
X39416Y206616D03*
X65500Y237800D03*
X70500D03*
X75500D03*
X23800Y211200D03*
X27500D03*
X59700Y178600D03*
X68400Y177950D03*
X76800Y178200D03*
X46194Y179835D03*
X50194D03*
X39320Y213823D03*
X64000Y178400D03*
X72800Y178200D03*
X22150Y203550D03*
X26150Y230850D03*
X33759Y274180D03*
X37830D03*
X23100Y292200D03*
Y287700D03*
X56026Y256117D03*
X23100Y283200D03*
X22750Y275450D03*
X23500Y296700D03*
X68300Y292200D03*
X45650Y250280D03*
X49320D03*
X40290Y239814D03*
X35405Y239808D03*
X32469Y250280D03*
X37469D03*
X69143Y334598D03*
X47443Y334198D03*
X27947Y334066D03*
X37049Y302949D03*
X23100Y318500D03*
Y314000D03*
X52450Y333850D03*
X31450Y334050D03*
X74150Y334250D03*
X28000Y326500D03*
X24000Y301750D03*
X23400Y309500D03*
X67800Y318000D03*
X67700Y321500D03*
X58900Y334180D03*
X62325Y334068D03*
X37900Y334380D03*
X41325Y334268D03*
X57350Y387800D03*
X46900Y378233D03*
X26100Y378352D03*
X69300Y378800D03*
X31240Y393440D03*
X49700Y391000D03*
X54040Y399390D03*
X65500Y378800D03*
X43000Y378233D03*
X22000Y378352D03*
X53500Y403150D03*
X49700Y402000D03*
X50700Y378233D03*
X54800Y373600D03*
X29900Y378252D03*
X38200Y373800D03*
X34100D03*
X73100Y378700D03*
X60400Y373600D03*
X77200Y374000D03*
X65375Y392835D03*
X35800Y363400D03*
X40100D03*
X92300Y199400D03*
Y209400D03*
Y204400D03*
X90800Y217900D03*
X82600Y232000D03*
X78850Y221000D03*
X87300Y230650D03*
X92300Y190900D03*
X81300Y178050D03*
X85700Y178000D03*
X92300Y194900D03*
X78800Y205900D03*
X92300Y213900D03*
X89800Y178000D03*
X81000Y291700D03*
X80896Y286695D03*
X80688Y281695D03*
Y276695D03*
X93884Y242333D03*
X90238Y334391D03*
X78600Y321700D03*
X78700Y317400D03*
X102300Y329100D03*
X95245Y334043D03*
X80700Y309400D03*
X80600Y304600D03*
Y334580D03*
X84025Y334468D03*
X102400Y333900D03*
X106500D03*
X89895Y378426D03*
X83232Y399956D03*
X85795Y378426D03*
X102395Y373793D03*
X93695Y378426D03*
X81300Y374000D03*
X98295Y373793D03*
X106709Y383400D03*
X112023Y383013D03*
X78171Y363195D03*
X82171D03*
X99266Y362988D03*
X103266D03*
X104900Y412200D03*
X102679Y391150D03*
X112638Y391197D03*
X107582Y391266D03*
X102850Y452650D03*
X94488Y489888D03*
X191000Y110000D03*
X182100Y105500D03*
X155991Y110061D03*
X200550Y111350D03*
X152800Y113400D03*
X164020Y101127D03*
X158612Y126645D03*
X198202Y135298D03*
X145900Y136500D03*
X196963Y122029D03*
X184600Y137400D03*
X195400Y147200D03*
X195500Y142400D03*
X201139Y121630D03*
X172800Y141001D03*
X180300Y175400D03*
X145585Y132451D03*
X197100Y298800D03*
X162522Y331774D03*
X196600Y306800D03*
X250137Y36053D03*
X242610Y53714D03*
X229000Y95000D03*
X234450Y73000D03*
X245250Y98250D03*
X261102Y77900D03*
X248169Y74454D03*
X223994Y63225D03*
X242727Y63391D03*
X261499Y55353D03*
X257499D03*
X241750Y98250D03*
X238867Y63650D03*
X255300Y72600D03*
X234693Y57400D03*
X255154Y69177D03*
X233759Y64752D03*
X220228Y63651D03*
X245800Y279200D03*
X207600Y292400D03*
X204400Y288700D03*
X248900Y282932D03*
X259629Y281000D03*
X242351Y282900D03*
X228300Y280900D03*
X219400Y279400D03*
X262800Y277835D03*
X242400Y289700D03*
X242402Y286300D03*
X225500Y278900D03*
X222320Y277658D03*
X207500Y278400D03*
X204997Y280702D03*
X253575Y320167D03*
X235500Y320100D03*
X218500Y320200D03*
X222000Y310600D03*
X231700Y320100D03*
X249775Y320167D03*
X214700Y320200D03*
X212198Y328316D03*
X208648Y328452D03*
X261365Y324351D03*
X245943Y326300D03*
X246100Y329700D03*
X230400Y326200D03*
Y329600D03*
X253245Y329698D03*
X253154Y326227D03*
X241556Y340111D03*
X237483Y339988D03*
X230000Y336500D03*
X233400Y336600D03*
X218400Y326600D03*
X218300Y330000D03*
X230400Y348000D03*
X255500Y423361D03*
X237600Y390500D03*
X261581Y370979D03*
X256172Y409530D03*
X261996Y365663D03*
X263250Y423411D03*
X257996Y365663D03*
X259800Y423400D03*
X256900Y380900D03*
X312840Y42398D03*
X325378Y50351D03*
Y35351D03*
X310065Y32397D03*
X270000Y29000D03*
Y33500D03*
Y38000D03*
Y42500D03*
X281700Y52285D03*
X285500D03*
X267188Y55192D03*
X296385Y108227D03*
X285361Y78015D03*
X281761D03*
X289161Y58068D03*
X277514D03*
X308591Y68928D03*
X304591D03*
X308591Y73074D03*
X311182Y58692D03*
X283385Y100227D03*
X287385D03*
X319533Y114283D03*
X291385Y100227D03*
X295385D03*
X306196Y110209D03*
X310711Y113820D03*
X314772Y108292D03*
X300311Y60800D03*
X300385Y108227D03*
X311182Y62800D03*
X272937Y90362D03*
X266895Y100227D03*
X306280Y82574D03*
X283393Y92325D03*
X301280Y82574D03*
X272937Y85862D03*
X304591Y73074D03*
X318773Y108083D03*
X278039Y82185D03*
X279385Y100227D03*
X292030Y90574D03*
X292385Y108227D03*
X280298Y95556D03*
X296280Y82574D03*
X324026Y115936D03*
X321343Y122343D03*
X321051Y134028D03*
X304529Y118792D03*
X317700Y275400D03*
X270143Y276969D03*
X323681Y259023D03*
X319881D03*
X284498Y299976D03*
X299635Y292650D03*
X317600Y278800D03*
X319543Y290159D03*
X303032Y289900D03*
X268400Y281000D03*
X266406Y277835D03*
X299635Y288650D03*
X292225Y288267D03*
X297021Y346579D03*
X287350Y351200D03*
X319550Y347169D03*
X305147Y354706D03*
X316050Y342200D03*
X287350Y357700D03*
X322500Y353700D03*
X301500Y337500D03*
X320650Y336456D03*
X306060Y337640D03*
X310200Y337600D03*
X294250Y325000D03*
X277150Y332000D03*
X273165Y320351D03*
X280800Y325000D03*
X290750D03*
X280217Y350927D03*
X269365Y320351D03*
X325500Y325400D03*
X314241Y308459D03*
X314300Y311900D03*
X308180Y305200D03*
X305628Y320511D03*
X301628D03*
X325500Y321400D03*
X314400Y327851D03*
X314045Y302900D03*
X314500Y324251D03*
X319100Y330600D03*
X305628Y324511D03*
X324100Y307814D03*
X265365Y324351D03*
X281150Y332000D03*
X288536Y314764D03*
X275696Y314340D03*
X308398Y386479D03*
X304205Y382450D03*
X304398Y386479D03*
X292800Y363800D03*
X300019Y379524D03*
X296079D03*
X325200Y365100D03*
X312398Y386479D03*
X266300Y412100D03*
X270618Y385867D03*
X268004Y424361D03*
X323448Y405064D03*
X266500Y364000D03*
X325651Y439668D03*
X325629Y443510D03*
X328600Y114400D03*
X328711Y108053D03*
X335722Y94574D03*
X329722D03*
X374616Y172378D03*
X370061Y172433D03*
X355500Y144500D03*
X342000Y141600D03*
X331649Y126111D03*
X339049Y124238D03*
X335994Y126119D03*
X341913Y145049D03*
X374915Y176442D03*
X359969Y124510D03*
X349911Y136954D03*
X341757Y211056D03*
X337157Y206052D03*
X335701Y223995D03*
X352047Y220590D03*
X357546Y230354D03*
X360710Y231897D03*
X376306Y182715D03*
X351723Y178499D03*
X354143Y183439D03*
X362260Y184360D03*
X364169Y188366D03*
X366460Y191794D03*
X368558Y194540D03*
X379415Y194608D03*
X370570Y198219D03*
X371124Y178760D03*
X372517Y182362D03*
X380400Y287400D03*
X382000Y296500D03*
X384600Y285600D03*
X368714Y261134D03*
X339500Y260400D03*
X327868Y290125D03*
X365996Y287265D03*
Y272841D03*
X366169Y246591D03*
X370669D03*
X338650Y281350D03*
X361996Y272841D03*
X379000Y272600D03*
X384300Y291100D03*
X346900Y281300D03*
X343100D03*
X357996Y272841D03*
X328134Y252720D03*
X376633Y261543D03*
X340280Y253765D03*
X358096Y262268D03*
X341998Y256700D03*
X368610Y257299D03*
X376633Y256851D03*
X385887Y305222D03*
X381396Y302610D03*
X335400Y337400D03*
X345700Y349773D03*
X337600Y349600D03*
X339000Y344700D03*
X330000Y345800D03*
X335882Y309823D03*
X327400Y342600D03*
X386159Y337080D03*
X368050Y337200D03*
X370250Y347600D03*
X379148Y337184D03*
X384341Y315377D03*
X377324Y302844D03*
X360050Y337200D03*
X348600Y323900D03*
X359400Y347200D03*
X375148Y337184D03*
X382600Y337200D03*
X344000Y316000D03*
X346500Y302500D03*
X356550Y337200D03*
X348596Y337250D03*
X347750Y315850D03*
X352396Y337200D03*
X331026Y303354D03*
X328100Y331300D03*
X329364Y316949D03*
X364050Y337200D03*
X374250Y347600D03*
X359200Y315800D03*
X355200D03*
X360300Y323900D03*
X363400Y315800D03*
X344000Y388500D03*
X340375Y365944D03*
X331765Y386535D03*
X367450Y409955D03*
X338000Y421000D03*
X367350Y406455D03*
X360000Y410000D03*
X337592Y405027D03*
X327365Y433732D03*
X337900Y431200D03*
X448300Y337500D03*
X444100Y341000D03*
X444200Y337600D03*
X444100Y345000D03*
X440300Y337500D03*
X444959Y352053D03*
X389559Y337103D03*
X421500Y337500D03*
X427500D03*
X448431Y348737D03*
X416822Y347133D03*
X412381Y347149D03*
X435000Y347800D03*
X441000D03*
X433500Y337500D03*
X426464Y347078D03*
X397000Y337000D03*
X401700Y337350D03*
X392959Y337099D03*
X405921Y347159D03*
X430464Y347078D03*
X390550Y326820D03*
X405783Y339318D03*
X448500Y424000D03*
X445000Y422000D03*
X490877Y176547D03*
X510427Y176431D03*
X500302Y176489D03*
X490877Y189047D03*
Y185047D03*
Y180547D03*
X510427Y188931D03*
Y184931D03*
Y180431D03*
X500302Y188989D03*
Y184989D03*
Y180489D03*
X452300Y337500D03*
X468300D03*
X456550D03*
X464300D03*
X460800Y337562D03*
X460300Y333500D03*
X481359Y347727D03*
X467774Y362151D03*
X467100Y357500D03*
X464500Y347410D03*
X502138Y348500D03*
X476500Y347650D03*
X498138Y348500D03*
X506200Y358809D03*
X493200Y358800D03*
X498700Y359209D03*
X452600Y332700D03*
X462450Y358960D03*
X472463Y329837D03*
X468500Y347500D03*
X476200Y334900D03*
X506262Y348500D03*
X510138D03*
X479640Y334674D03*
X485100Y366800D03*
X490000Y363700D03*
X502850Y368500D03*
X503800Y382700D03*
X473900Y371800D03*
X485100Y363400D03*
X510200Y363209D03*
X506200D03*
X494400Y363800D03*
X499100Y363409D03*
X452500Y423500D03*
X510700Y367309D03*
X506700D03*
X489600Y367209D03*
X474200Y367500D03*
X457599Y419642D03*
X496300Y378935D03*
X489500Y371200D03*
X520552Y176373D03*
X557500Y231900D03*
X553500D03*
X549000D03*
X545000D03*
X520552Y188873D03*
Y184873D03*
Y180373D03*
X554717Y255796D03*
X550717D03*
X546217D03*
X542217D03*
X554975Y248209D03*
X550975D03*
X546475D03*
X542475D03*
X555865Y240638D03*
X551865D03*
X547365D03*
X543365D03*
X542627Y324049D03*
X546627D03*
X551127D03*
X555127D03*
X541278Y315738D03*
X545278D03*
X549778D03*
X553778D03*
X541221Y308771D03*
X545221D03*
X549721D03*
X553721D03*
X541193Y301280D03*
X545193D03*
X549693D03*
X553693D03*
X552200Y339300D03*
X556800D03*
X547225Y357997D03*
X547379Y338352D03*
X539900Y338300D03*
X534000Y338400D03*
X538225Y357997D03*
X555697Y356565D03*
X514000Y359209D03*
X514138Y348500D03*
X518138Y348350D03*
X525438Y350500D03*
X519263Y327092D03*
X538476Y334365D03*
X538436Y330918D03*
X534100Y342410D03*
X536200Y348300D03*
X540200D03*
X550100D03*
X546100D03*
X554685Y333410D03*
X547927Y342199D03*
X543646Y342347D03*
X539446D03*
X519629Y330448D03*
X521914Y332907D03*
X557411Y481025D03*
X554250Y457500D03*
X574250Y466900D03*
X545880Y485940D03*
X539040Y480090D03*
X562460Y457580D03*
X517125Y488975D03*
X629813Y27661D03*
X631864Y51848D03*
X632416Y31609D03*
X627603Y43523D03*
X627500Y19339D03*
X626786Y31227D03*
X635942Y97351D03*
X634400Y102000D03*
X630600D03*
X627500Y64500D03*
X629500Y61500D03*
X590537Y170119D03*
X589706Y174031D03*
X586912Y154495D03*
X586081Y158407D03*
X585145Y162809D03*
X584314Y166721D03*
X596233Y145667D03*
X595402Y149579D03*
X594466Y153981D03*
X593635Y157893D03*
X588901Y134308D03*
X588070Y138220D03*
X587134Y142622D03*
X586303Y146534D03*
X577699Y123469D03*
X576868Y127381D03*
X575932Y131783D03*
X575101Y135695D03*
X634169Y166500D03*
X618250Y162081D03*
X618400Y173443D03*
X617600Y134400D03*
X635852Y133715D03*
X589966Y210195D03*
X589135Y214107D03*
X588199Y218509D03*
X587368Y222421D03*
X585841Y194571D03*
X585010Y198483D03*
X584074Y202885D03*
X583243Y206797D03*
X581716Y178947D03*
X580885Y182859D03*
X579949Y187261D03*
X579118Y191173D03*
X588770Y178433D03*
X587939Y182345D03*
X627455Y185364D03*
X634000Y234200D03*
X630000D03*
X636363Y209944D03*
X632363D03*
X628363D03*
X624363D03*
X622400Y216750D03*
X598600Y247800D03*
Y253100D03*
X633800Y239600D03*
X629900Y239700D03*
X633800Y245700D03*
X629900Y245800D03*
X634100Y252000D03*
X629900D03*
X594025Y284017D03*
X618300Y288745D03*
X632750Y292195D03*
Y295641D03*
X594025Y280017D03*
X590050Y337950D03*
X590200Y334350D03*
X610750Y336850D03*
X594050Y301755D03*
X632750Y330854D03*
Y334300D03*
X618300Y327654D03*
X632900Y344950D03*
X612300Y356850D03*
X608500Y315000D03*
X634000Y306300D03*
X631800Y316137D03*
X603650Y315500D03*
X594292Y362291D03*
X625000Y361700D03*
X590350Y323011D03*
X629250Y310491D03*
Y306491D03*
X626405Y314991D03*
X629250Y344900D03*
Y348900D03*
X623063Y357337D03*
X602649Y349033D03*
X594400Y357000D03*
Y353000D03*
X597450Y324750D03*
Y320750D03*
X627020Y393364D03*
X598152Y370130D03*
X629770Y369320D03*
X594200Y390400D03*
X629400Y414324D03*
X584280Y424030D03*
X598023Y383081D03*
X624200Y372500D03*
X620260Y389940D03*
X589394Y384572D03*
X589391Y378202D03*
X627140Y381353D03*
X631140D03*
X630000Y464900D03*
X626300D03*
X577330Y464430D03*
X599900Y438300D03*
X587890Y426720D03*
X581020Y471890D03*
X574667Y479799D03*
X577300Y460300D03*
X588400Y469450D03*
X634050Y469200D03*
X588663Y460037D03*
X581250Y480550D03*
X585420Y456480D03*
X633676Y460080D03*
X617000Y468700D03*
X588030Y430795D03*
X620600Y458500D03*
X652551Y40716D03*
X656450Y28000D03*
X655914Y39932D03*
X667149Y23411D03*
X656300Y20100D03*
X660200Y20200D03*
X647216Y31601D03*
X667900Y40800D03*
X643816Y31573D03*
X643103Y13803D03*
X664301Y40104D03*
Y49998D03*
X638103Y13100D03*
X640416Y31609D03*
X647103Y13964D03*
X694365Y98458D03*
Y94458D03*
Y90958D03*
Y86958D03*
X686279Y98494D03*
Y94494D03*
Y90994D03*
Y86994D03*
X678225Y98496D03*
Y94496D03*
Y90996D03*
Y86996D03*
X670146Y98505D03*
Y94505D03*
Y91005D03*
Y87005D03*
X662047Y98539D03*
Y94539D03*
Y91039D03*
Y87039D03*
X654037Y98708D03*
Y94708D03*
Y91208D03*
Y87208D03*
X637003Y68809D03*
X648207Y70750D03*
X654330Y113385D03*
X688976D03*
X646643Y97859D03*
X644100Y111811D03*
X668100Y56100D03*
X651564Y52638D03*
X644500Y65759D03*
X657480Y113385D03*
X678189Y108784D03*
X689049Y109487D03*
X669500Y108400D03*
X640600Y111600D03*
X641003Y68809D03*
X654330Y154330D03*
X657480Y151219D03*
X663778Y166928D03*
X673227Y157479D03*
X673229Y166929D03*
Y173228D03*
X670080Y148030D03*
X679526Y144880D03*
X660629Y138584D03*
Y141732D03*
X688978Y135435D03*
X682679D03*
X676379D03*
X695274Y135431D03*
X698425Y129134D03*
X663778Y160629D03*
Y154330D03*
Y135431D03*
X692124D03*
X673227Y144880D03*
X685825Y138581D03*
X679526D03*
X673227D03*
X666928D03*
X648032Y129134D03*
X657480Y122834D03*
X698425Y135433D03*
Y138582D03*
X692125D03*
X682677Y148031D03*
X688976D03*
X695275D03*
X682677Y154330D03*
X688976D03*
X695275D03*
Y160629D03*
X688976D03*
X682677Y160630D03*
X679527Y163779D03*
X695275Y166929D03*
X688976D03*
X682677D03*
X695275Y173228D03*
X688976D03*
X682677D03*
X654330Y170078D03*
X648031Y163779D03*
X654330D03*
X651181Y157480D03*
X670078Y154330D03*
X644882Y157480D03*
X666929Y125984D03*
X657480Y129134D03*
X651181Y151181D03*
X698425Y116535D03*
X648059Y151191D03*
X685827Y125985D03*
X676377Y116536D03*
X663778Y176377D03*
Y173227D03*
Y170078D03*
X670078Y166928D03*
Y173227D03*
X654330Y176377D03*
X639108Y167800D03*
X648057Y141721D03*
X648032Y135434D03*
Y122835D03*
X660629Y116536D03*
X666929Y116535D03*
X698426Y122835D03*
X692148Y129119D03*
X670116Y132283D03*
X673229Y125985D03*
X679528D03*
X660629Y170078D03*
Y173227D03*
X654330Y157480D03*
X651181Y154330D03*
X673229Y170079D03*
X679527Y173229D03*
X692126Y141732D03*
X698425D03*
X679527Y148031D03*
X685826D03*
X692126D03*
X698425D03*
X679527Y154330D03*
X685826D03*
X692126D03*
X698425D03*
Y160629D03*
X692126D03*
X685826D03*
X679527D03*
X698425Y166929D03*
X692126D03*
X685826D03*
X679527D03*
X698425Y173228D03*
X692126D03*
X685826D03*
X670078Y170078D03*
X654330Y173228D03*
X651181Y166929D03*
X676376Y132281D03*
X666929Y129134D03*
X660630Y160630D03*
X640775Y156218D03*
X648031Y157480D03*
X663779Y151181D03*
X666929Y148031D03*
X663779Y132283D03*
X663778Y144883D03*
Y138584D03*
X651181Y141732D03*
Y132283D03*
Y122834D03*
X644882Y154331D03*
X637952Y142515D03*
X640500Y125000D03*
X660629Y144883D03*
X657481Y132284D03*
X670078Y151181D03*
X637343Y171335D03*
Y174835D03*
X657480Y154330D03*
X644882Y173228D03*
Y176378D03*
Y170078D03*
X648031D03*
X670078Y157480D03*
X673228Y148031D03*
X692126Y125984D03*
X685827Y116535D03*
X670079Y125985D03*
X682678D03*
X676378D03*
X688977D03*
X676378Y119686D03*
X666929Y119685D03*
X663780Y125985D03*
X657479Y116536D03*
X654330Y116535D03*
Y119685D03*
Y122834D03*
X657480Y125984D03*
X654331D03*
X654330Y129134D03*
Y132283D03*
Y135433D03*
X651181D03*
X654330Y138582D03*
Y141732D03*
Y144882D03*
X651181D03*
X654330Y148031D03*
Y151181D03*
X679452Y209815D03*
X651181Y188976D03*
X679527Y182679D03*
Y188975D03*
X676379Y182678D03*
X692126Y182676D03*
Y185827D03*
Y179527D03*
X676379Y192126D03*
X670080Y182678D03*
X697069Y207157D03*
X663400Y234100D03*
X663200Y238100D03*
X682676Y179526D03*
Y188975D03*
X682677Y182677D03*
X682676Y185826D03*
X676377Y201574D03*
Y204723D03*
X685826Y198424D03*
X663778Y182676D03*
Y179526D03*
X654330Y182676D03*
X660629Y192125D03*
X666929D03*
X660630Y198425D03*
X676377Y198424D03*
X685826Y201574D03*
X682677Y192125D03*
X688976D03*
X698425D03*
X640931Y181102D03*
X646594Y210875D03*
X640584Y194127D03*
X683913Y213313D03*
X695275Y198425D03*
X692125Y198423D03*
X686352Y207200D03*
X651181Y192125D03*
X663779D03*
X657480D03*
X670078D03*
X654330Y185826D03*
Y179526D03*
X685826Y192125D03*
X692125D03*
X667353Y233486D03*
X640363Y209944D03*
X638479Y230640D03*
X674023Y213815D03*
X640509Y177600D03*
X674172Y210095D03*
X679400Y213300D03*
X679527Y198424D03*
X697149Y219742D03*
X692949D03*
X695600Y240354D03*
X682700D03*
X695625Y282250D03*
X669125Y280405D03*
X663000Y249200D03*
X663100Y252700D03*
X674841Y262854D03*
X695383Y266855D03*
X644153Y278745D03*
X660400Y271900D03*
X678500Y240324D03*
X691100Y240354D03*
X686900D03*
X668600Y242800D03*
X669450Y284900D03*
X695600Y244354D03*
X695375Y260875D03*
X637500Y362400D03*
X680300Y384900D03*
X662306Y365477D03*
X657673Y365400D03*
X672281Y378883D03*
X693500Y373300D03*
X694765Y406915D03*
X685750Y419460D03*
X642900Y395400D03*
X674150Y415380D03*
X654770Y401166D03*
X645970Y399130D03*
X669031Y388383D03*
X665031D03*
X653360Y386210D03*
X680700Y378200D03*
X687150Y385550D03*
X675031Y389383D03*
X653007Y382828D03*
X658601Y401800D03*
X673900Y418880D03*
X637500Y365900D03*
X672800Y438832D03*
X696950Y441400D03*
X667414Y431956D03*
X692200Y428700D03*
X681540Y429640D03*
X678700Y440950D03*
X671640Y454410D03*
X683250Y437813D03*
X710378Y100399D03*
Y96399D03*
Y92899D03*
Y88899D03*
X702391Y98510D03*
Y94510D03*
Y91010D03*
Y87010D03*
X728788Y88540D03*
X725295Y88609D03*
X752853Y100900D03*
X722673Y105444D03*
X736785Y110185D03*
X737800Y106525D03*
X717197Y109646D03*
X726100Y107200D03*
X734709Y106595D03*
X731000Y106315D03*
X734212Y109995D03*
X725943Y100147D03*
X744833Y78995D03*
X754572Y86923D03*
X754528Y83228D03*
X745100Y97500D03*
X699563Y108815D03*
X719010Y107281D03*
X707649Y110002D03*
X710517Y106823D03*
X750773Y74636D03*
X747919Y76667D03*
X720744Y92427D03*
X704849Y107385D03*
X733069Y166930D03*
X704725Y135434D03*
X707874Y141732D03*
X701574Y138582D03*
X701575Y135433D03*
X711023Y132283D03*
X704724D03*
X717322Y129133D03*
X726770Y166930D03*
Y173229D03*
X701574Y148031D03*
X707873D03*
X701574Y154330D03*
X707873D03*
Y160629D03*
X701574D03*
X707873Y166929D03*
X701574D03*
X707873Y173228D03*
X701574D03*
X711023Y122834D03*
X717322D03*
X723622D03*
X711023Y141732D03*
X743452Y151815D03*
X714172Y173227D03*
Y144880D03*
Y151180D03*
X717322Y144880D03*
Y151180D03*
X714172Y163778D03*
Y157479D03*
X717322Y163778D03*
Y157479D03*
Y166928D03*
X720472Y173228D03*
Y148031D03*
Y141732D03*
Y160629D03*
Y154330D03*
X720471Y166928D03*
X717322Y141731D03*
X758050Y164050D03*
X704725Y122835D03*
X720472Y135433D03*
X729921Y157480D03*
X739952Y120649D03*
X740952Y126815D03*
X707874Y116535D03*
X743100Y114700D03*
X737352Y145885D03*
X726771Y122835D03*
X729921Y122834D03*
X737702Y128565D03*
X729921Y132283D03*
Y129134D03*
X711023Y116535D03*
X726771Y163779D03*
X741754Y134617D03*
X729921Y135433D03*
X739622Y137008D03*
X729921Y138582D03*
Y144882D03*
X714173Y116535D03*
X717322D03*
X707873Y129133D03*
X720473Y116536D03*
X704725D03*
X704724Y148031D03*
Y154330D03*
Y160629D03*
Y166929D03*
Y173228D03*
X714173Y122834D03*
X720472D03*
X741077Y159790D03*
X757471Y148193D03*
X723621Y148031D03*
Y154330D03*
Y160629D03*
Y166929D03*
Y173228D03*
X707874Y122835D03*
X723621Y135433D03*
Y129133D03*
Y141732D03*
X701575Y122835D03*
X714173Y141732D03*
X723622Y116535D03*
X704723Y129133D03*
X701574D03*
X711022D03*
X714172D03*
X729921Y125984D03*
X711023Y173228D03*
X741952Y173115D03*
X738352Y174615D03*
X729920Y176378D03*
Y173229D03*
X736219Y170079D03*
X733070D03*
X746750Y157700D03*
X729921Y148031D03*
Y141732D03*
Y163779D03*
X750550Y135200D03*
X729921Y160629D03*
X701575Y116536D03*
X729921Y154330D03*
X717322Y182676D03*
X711024Y188976D03*
X701575Y182676D03*
X711022Y185825D03*
X701575Y185827D03*
Y179527D03*
X726770Y179528D03*
Y185827D03*
X743200Y227900D03*
X726770Y192126D03*
X730694Y224473D03*
X726656Y235244D03*
X711022Y179526D03*
X714172D03*
X722523Y221315D03*
X720437Y185829D03*
X720472Y179527D03*
Y192125D03*
X711022Y182676D03*
X704724Y192125D03*
X711024D03*
X730737Y235199D03*
X724465Y224741D03*
X714620Y221041D03*
X743460Y231900D03*
X701574Y192125D03*
X707873D03*
X714173D03*
X723621D03*
Y185826D03*
Y179527D03*
X715467Y210507D03*
X725009Y213292D03*
X739852Y195915D03*
X737832Y202664D03*
X729920Y188977D03*
X739752Y199615D03*
X738416Y190551D03*
X729920Y182678D03*
X745485Y197673D03*
Y201673D03*
X740352Y180115D03*
X729920Y185827D03*
X724776Y209963D03*
X743752Y187115D03*
X742502Y182715D03*
X742252Y177015D03*
X737315Y177952D03*
X733070Y179527D03*
X720819Y209800D03*
X729246Y209941D03*
X736272Y208181D03*
X729136Y206654D03*
X738839Y206080D03*
X733565Y210184D03*
X729920Y192126D03*
X720357Y207104D03*
X714173Y198425D03*
X729921Y179527D03*
X720471Y198424D03*
X731915Y206310D03*
X738952Y184215D03*
X744052Y193784D03*
X701574Y198424D03*
X711023Y198425D03*
X704724D03*
X717322D03*
X707873Y198424D03*
X723621D03*
X704724Y201574D03*
X706737Y205505D03*
X705336Y208437D03*
X711310Y207023D03*
X714173Y201574D03*
X718330Y205172D03*
X704708Y264647D03*
X751878Y276817D03*
X749620Y273620D03*
X707574Y276558D03*
X712720Y240976D03*
X754227Y297611D03*
X739300Y287611D03*
X751693Y255540D03*
X743507Y251685D03*
X747558Y247274D03*
X759558Y241027D03*
Y247274D03*
X731300Y287611D03*
X735300D03*
X731318Y283571D03*
X735318D03*
X731155Y279636D03*
X739318Y283571D03*
X734638Y275696D03*
X751693Y259540D03*
X755693D03*
X704708Y256647D03*
Y252647D03*
X753560Y273780D03*
X704708Y260647D03*
X751133Y313984D03*
X754227Y301111D03*
X705320Y420610D03*
X735570Y424760D03*
X721380Y423930D03*
X739680Y423900D03*
X700200Y388200D03*
Y384800D03*
X718110Y442960D03*
X708355Y454712D03*
X701120Y430620D03*
X719920Y429700D03*
X743480Y439080D03*
X710200Y441200D03*
X706120Y441410D03*
X729870Y451300D03*
X740900Y456400D03*
X700855Y426719D03*
X799250Y71125D03*
X772107Y83046D03*
X799493Y93250D03*
X761650Y89937D03*
X771610Y93040D03*
X799500Y106000D03*
X781000Y88000D03*
Y84200D03*
X788287Y86087D03*
X768250Y106300D03*
X768100Y109700D03*
X763560Y59820D03*
X767359Y82076D03*
X782500Y134283D03*
X773000Y119600D03*
X776600D03*
X794500Y134283D03*
X785000Y158900D03*
X760600Y173700D03*
X804320Y134300D03*
X804400Y175000D03*
X760800Y169550D03*
X769600Y164200D03*
X765200Y135750D03*
X786500Y134283D03*
X763050Y154100D03*
X761400Y160050D03*
X764600Y141500D03*
X768700Y129800D03*
X768900Y134800D03*
X760715Y210200D03*
X804412Y185332D03*
X800612Y185432D03*
X760715Y201700D03*
Y214200D03*
X790000Y224700D03*
X760715Y197200D03*
X764550Y182900D03*
X764750Y179300D03*
X761550Y180500D03*
X786400Y179000D03*
X779200Y178650D03*
X790714Y237308D03*
X801618Y210116D03*
Y214116D03*
X795498Y246171D03*
X793912Y297020D03*
X793837Y283696D03*
X781640Y278660D03*
X786006Y283383D03*
X781640Y282160D03*
X793837Y291696D03*
X805254Y263886D03*
X761484Y255581D03*
Y251581D03*
X780837Y240885D03*
X774637Y267746D03*
X770637D03*
X761638Y259635D03*
X774637Y259746D03*
Y263746D03*
X793837Y279636D03*
Y275696D03*
X780837Y267826D03*
X784837Y263891D03*
Y259951D03*
X793852Y256011D03*
Y252076D03*
X793837Y271761D03*
Y267826D03*
Y263696D03*
X774657Y255999D03*
X765638Y255635D03*
X774637Y251876D03*
X784837Y271761D03*
Y267826D03*
X793837Y287696D03*
X780837Y271761D03*
X801853Y300515D03*
X767890Y273380D03*
X763292Y287630D03*
X786610Y321340D03*
X786300Y309900D03*
X761520Y339110D03*
X765764Y326844D03*
X801728Y304572D03*
X776497Y338392D03*
X775672Y350204D03*
X782770Y321200D03*
G54D32*
X251200Y415000D03*
X312500Y290100D03*
X338600Y285800D03*
Y277770D03*
X377171Y332810D03*
X472700Y270600D03*
X472600Y262500D03*
X472900Y249200D03*
X472800Y254800D03*
X554200Y461260D03*
X516600Y456800D03*
X604926Y234952D03*
X647654Y138591D03*
X646717Y116114D03*
Y119614D03*
X673152Y150915D03*
Y154415D03*
X682602Y145315D03*
X682600Y151100D03*
X682500Y157350D03*
X660600Y128650D03*
X696052Y194895D03*
X640600Y238400D03*
X718333Y195408D03*
X703662Y195365D03*
G54D41*
X290000Y136500D03*
Y147500D03*
Y167500D03*
Y156500D03*
Y239500D03*
Y209000D03*
Y198000D03*
Y220000D03*
Y231000D03*
Y178500D03*
Y189500D03*
Y250500D03*
G54D23*
X158267Y25708D03*
X145669D03*
X158267Y47362D03*
X145669D03*
X158267Y53267D03*
Y41456D03*
Y31614D03*
Y19803D03*
X145669D03*
Y31614D03*
Y41456D03*
Y53267D03*
G54D14*
X38502Y161319D03*
X49302D03*
X43902D03*
X49302Y150519D03*
Y155919D03*
X43902Y150519D03*
Y155919D03*
X38502D03*
Y150519D03*
X108672Y138471D03*
Y132871D03*
X90672Y138471D03*
X102672D03*
X96672D03*
X84672D03*
Y132871D03*
X96672D03*
X102672D03*
X90672D03*
G54D50*
X388189Y48426D03*
X374016D03*
X359843D03*
X345670D03*
X388189Y34252D03*
X374016D03*
X359843D03*
X345670D03*
X388189Y20079D03*
X374016D03*
X359843D03*
X345670D03*
X388189Y44095D03*
X374016D03*
X359843D03*
X345670D03*
X388189Y38583D03*
X374016D03*
X359843D03*
X345670D03*
X388189Y29922D03*
X374016D03*
X359843D03*
X345670D03*
X388189Y24410D03*
X374016D03*
X359843D03*
X345670D03*
X388189Y15748D03*
X374016D03*
X359843D03*
X345670D03*
X388189Y10237D03*
X374016D03*
X359843D03*
X345670D03*
X388189Y5906D03*
X374016D03*
X359843D03*
X345670D03*
X381103Y38977D03*
X366929D03*
X352756D03*
X338583D03*
X381103Y24804D03*
X366929D03*
X352756D03*
X338583D03*
X381103Y53150D03*
X366929D03*
X352756D03*
X338583D03*
X381103Y48819D03*
X366929D03*
X352756D03*
X338583D03*
X381103Y43307D03*
X366929D03*
X352756D03*
X338583D03*
X381103Y34646D03*
X366929D03*
X352756D03*
X338583D03*
X381103Y29134D03*
X366929D03*
X352756D03*
X338583D03*
X381103Y20473D03*
X366929D03*
X352756D03*
X338583D03*
X381103Y14961D03*
X366929D03*
X352756D03*
X338583D03*
X444882Y48426D03*
X430709D03*
X416536D03*
X402363D03*
X444882Y34252D03*
X430709D03*
X416536D03*
X402363D03*
X444882Y20079D03*
X430709D03*
X416536D03*
X402363D03*
X444882Y44095D03*
X430709D03*
X416536D03*
X402363D03*
X444882Y38583D03*
X430709D03*
X416536D03*
X402363D03*
X444882Y29922D03*
X430709D03*
X416536D03*
X402363D03*
X444882Y24410D03*
X430709D03*
X416536D03*
X402363D03*
X444882Y15748D03*
X430709D03*
X416536D03*
X402363D03*
X444882Y10237D03*
X430709D03*
X416536D03*
X402363D03*
X444882Y5906D03*
X430709D03*
X416536D03*
X402363D03*
X437796Y38977D03*
X423622D03*
X409449D03*
X395276D03*
X437796Y24804D03*
X423622D03*
X409449D03*
X395276D03*
X437796Y53150D03*
X423622D03*
X409449D03*
X395276D03*
X437796Y48819D03*
X423622D03*
X409449D03*
X395276D03*
X437796Y43307D03*
X423622D03*
X409449D03*
X395276D03*
X437796Y34646D03*
X423622D03*
X409449D03*
X395276D03*
X437796Y29134D03*
X423622D03*
X409449D03*
X395276D03*
X437796Y20473D03*
X423622D03*
X409449D03*
X395276D03*
X437796Y14961D03*
X423622D03*
X409449D03*
X395276D03*
X501575Y48426D03*
X487402D03*
X473229D03*
X459055D03*
X501575Y34252D03*
X487402D03*
X473229D03*
X459055D03*
X501575Y20079D03*
X487402D03*
X473229D03*
X459055D03*
X501575Y44095D03*
X487402D03*
X473229D03*
X459055D03*
X501575Y38583D03*
X487402D03*
X473229D03*
X459055D03*
X501575Y29922D03*
X487402D03*
X473229D03*
X459055D03*
X501575Y24410D03*
X487402D03*
X473229D03*
X459055D03*
X501575Y15748D03*
X487402D03*
X473229D03*
X459055D03*
X501575Y10237D03*
X487402D03*
X473229D03*
X459055D03*
X501575Y5906D03*
X487402D03*
X473229D03*
X459055D03*
X508662Y38977D03*
X494489D03*
X480315D03*
X466142D03*
X451969D03*
X508662Y24804D03*
X494489D03*
X480315D03*
X466142D03*
X451969D03*
X508662Y53150D03*
X494489D03*
X480315D03*
X466142D03*
X451969D03*
X508662Y48819D03*
X494489D03*
X480315D03*
X466142D03*
X451969D03*
X508662Y43307D03*
X494489D03*
X480315D03*
X466142D03*
X451969D03*
X508662Y34646D03*
X494489D03*
X480315D03*
X466142D03*
X451969D03*
X508662Y29134D03*
X494489D03*
X480315D03*
X466142D03*
X451969D03*
X508662Y20473D03*
X494489D03*
X480315D03*
X466142D03*
X451969D03*
X508662Y14961D03*
X494489D03*
X480315D03*
X466142D03*
X451969D03*
X572441Y48426D03*
X558268D03*
X544095D03*
X529922D03*
X515748D03*
X572441Y34252D03*
X558268D03*
X544095D03*
X529922D03*
X515748D03*
X572441Y20079D03*
X558268D03*
X544095D03*
X529922D03*
X515748D03*
X572441Y44095D03*
X558268D03*
X544095D03*
X529922D03*
X515748D03*
X572441Y38583D03*
X558268D03*
X544095D03*
X529922D03*
X515748D03*
X572441Y29922D03*
X558268D03*
X544095D03*
X529922D03*
X515748D03*
X572441Y24410D03*
X558268D03*
X544095D03*
X529922D03*
X515748D03*
X572441Y15748D03*
X558268D03*
X544095D03*
X529922D03*
X515748D03*
X572441Y10237D03*
X558268D03*
X544095D03*
X529922D03*
X515748D03*
X572441Y5906D03*
X558268D03*
X544095D03*
X529922D03*
X515748D03*
X565355Y38977D03*
X551181D03*
X537008D03*
X522835D03*
X565355Y24804D03*
X551181D03*
X537008D03*
X522835D03*
X565355Y53150D03*
X551181D03*
X537008D03*
X522835D03*
X565355Y48819D03*
X551181D03*
X537008D03*
X522835D03*
X565355Y43307D03*
X551181D03*
X537008D03*
X522835D03*
X565355Y34646D03*
X551181D03*
X537008D03*
X522835D03*
X565355Y29134D03*
X551181D03*
X537008D03*
X522835D03*
X565355Y20473D03*
X551181D03*
X537008D03*
X522835D03*
X565355Y14961D03*
X551181D03*
X537008D03*
X522835D03*
X586614Y48426D03*
Y34252D03*
Y20079D03*
Y44095D03*
Y38583D03*
Y29922D03*
Y24410D03*
Y15748D03*
Y10237D03*
Y5906D03*
X579528Y38977D03*
Y24804D03*
Y53150D03*
Y48819D03*
Y43307D03*
Y34646D03*
Y29134D03*
Y20473D03*
Y14961D03*
X758267Y48426D03*
X744094D03*
X729921D03*
X715748D03*
X758267Y44095D03*
X744094D03*
X729921D03*
X715748D03*
X758267Y38583D03*
X744094D03*
X729921D03*
X715748D03*
X758267Y34252D03*
X744094D03*
X729921D03*
X715748D03*
X758267Y29922D03*
X744094D03*
X729921D03*
X715748D03*
X758267Y24410D03*
X744094D03*
X729921D03*
X715748D03*
X758267Y20079D03*
X744094D03*
X729921D03*
X715748D03*
X758267Y15748D03*
X744094D03*
X729921D03*
X715748D03*
X758267Y10237D03*
X744094D03*
X729921D03*
X715748D03*
X758267Y5906D03*
X744094D03*
X729921D03*
X715748D03*
X751181Y53150D03*
X737007D03*
X722834D03*
X708661D03*
X751181Y48819D03*
X737007D03*
X722834D03*
X708661D03*
X751181Y43307D03*
X737007D03*
X722834D03*
X708661D03*
X751181Y38977D03*
X737007D03*
X722834D03*
X708661D03*
X751181Y34646D03*
X737007D03*
X722834D03*
X708661D03*
X751181Y29134D03*
X737007D03*
X722834D03*
X708661D03*
X751181Y24804D03*
X737007D03*
X722834D03*
X708661D03*
X751181Y20473D03*
X737007D03*
X722834D03*
X708661D03*
X751181Y14961D03*
X737007D03*
X722834D03*
X708661D03*
G54D60*
X377683Y314895D03*
X399258Y262952D03*
X429389Y267240D03*
X409550Y330250D03*
X436786Y351341D03*
X408020Y335630D03*
X498500Y194800D03*
X486644Y354873D03*
X478400Y367500D03*
Y363400D03*
X495100Y368350D03*
X542295Y480090D03*
X570633Y476488D03*
X566539Y461261D03*
X654313Y166929D03*
X684800Y210200D03*
X669500Y288000D03*
X678789Y268500D03*
X759170Y81900D03*
X759140Y77810D03*
X759170Y86100D03*
X736879Y155899D03*
X712646Y276558D03*
G54D24*
X149858Y418270D03*
X261712Y59618D03*
X619226Y234952D03*
X581700Y449500D03*
X660145Y23414D03*
X667177Y135318D03*
X667118Y141825D03*
X698089Y169842D03*
X684200Y128700D03*
X676582Y128735D03*
X641123Y144911D03*
X641150Y134900D03*
X641100Y148800D03*
X671092Y195715D03*
X663412Y195705D03*
X654400Y238400D03*
X684512Y480221D03*
X704988Y145327D03*
X705610Y169842D03*
X726055Y195527D03*
X721304Y329638D03*
G54D15*
X45000Y203000D03*
G54D33*
X254300Y363700D03*
X300500Y138700D03*
X301000Y223200D03*
X300500Y180700D03*
X362810Y249340D03*
X362868Y277487D03*
X362677Y305262D03*
X581500Y459200D03*
X676531Y379833D03*
X788107Y122593D03*
G54D42*
X287500Y289700D03*
X358298Y253844D03*
X358342Y281987D03*
X358214Y310062D03*
X409100Y344000D03*
X421500Y344500D03*
X440740Y344644D03*
X435200Y334000D03*
X427500Y334100D03*
X421500Y334200D03*
X396000Y344100D03*
X467900Y354200D03*
X474577Y342865D03*
X496100Y355300D03*
X497206Y345231D03*
X464000Y344200D03*
X460000D03*
X451300Y344300D03*
X491445Y350358D03*
X477400Y354300D03*
X468000Y344200D03*
X486873Y350356D03*
X472000Y354200D03*
X482618Y342842D03*
X513517Y345246D03*
X521522D03*
X517517D03*
X518500Y355700D03*
X522500D03*
X549400Y489390D03*
X631500Y108700D03*
X632300Y158100D03*
X644710Y26267D03*
X637003Y65709D03*
X689468Y250105D03*
X691887Y267877D03*
X657031Y380083D03*
X666031D03*
X661531D03*
X698541Y202589D03*
X785350Y95200D03*
X781000D03*
X802696Y140800D03*
X786500D03*
X790500D03*
X796110Y186300D03*
X792000Y232700D03*
G54D51*
X381103Y10651D03*
X366929D03*
X352756D03*
X338583D03*
X437796D03*
X423622D03*
X409449D03*
X395276D03*
X410236Y419291D03*
Y404331D03*
Y449212D03*
Y434252D03*
X508661Y10651D03*
X494488D03*
X480315D03*
X466142D03*
X451969D03*
X565354D03*
X551181D03*
X537008D03*
X522835D03*
X579527D03*
X751181D03*
X737007D03*
X722834D03*
X708661D03*
G54D70*
X532812Y444771D03*
X537812D03*
X542812D03*
X547812D03*
Y464771D03*
X542812D03*
X537812D03*
X532812D03*
X800000Y172000D03*
X795000D03*
X790000D03*
X785000D03*
Y152000D03*
X790000D03*
X795000D03*
X800000D03*
G54D52*
X380500Y173000D03*
Y175200D03*
X382700Y173000D03*
Y175200D03*
X386500Y173000D03*
Y175200D03*
X388700Y173000D03*
Y175200D03*
X392500Y173000D03*
Y175200D03*
X394700Y173000D03*
Y175200D03*
X398500Y173000D03*
Y175200D03*
X400700Y173000D03*
Y175200D03*
X404500Y173000D03*
Y175200D03*
X406700Y173000D03*
Y175200D03*
X412700Y173000D03*
Y175200D03*
X410500Y173000D03*
Y175200D03*
X416500Y173000D03*
Y175200D03*
X418700Y173000D03*
Y175200D03*
X422500Y173000D03*
Y175200D03*
X428500Y173000D03*
Y175200D03*
X424700Y173000D03*
Y175200D03*
X430700Y173000D03*
Y175200D03*
X434500Y173000D03*
Y175200D03*
X436700Y173000D03*
Y175200D03*
X440500Y173000D03*
Y175200D03*
X442700Y173000D03*
Y175200D03*
X446500Y173000D03*
Y175200D03*
X448700Y173000D03*
Y175200D03*
X423297Y257900D03*
Y260100D03*
X407500Y253900D03*
Y256100D03*
X419300Y257900D03*
Y260100D03*
X411400Y253900D03*
Y256100D03*
X442500Y276000D03*
Y278200D03*
X440000Y276000D03*
Y278200D03*
X447500Y276000D03*
Y278200D03*
X452500Y173000D03*
Y175200D03*
X454700Y173000D03*
Y175200D03*
X458500Y173000D03*
Y175200D03*
X460700Y173000D03*
Y175200D03*
X464500Y173000D03*
Y175200D03*
X466700Y173000D03*
Y175200D03*
X470500Y173000D03*
Y175200D03*
X472700Y173000D03*
Y175200D03*
X478100Y154300D03*
Y156500D03*
X480400Y154300D03*
Y156500D03*
X485100Y154300D03*
Y156500D03*
X487400Y154300D03*
Y156500D03*
X492100Y154300D03*
Y156500D03*
X494400Y154300D03*
Y156500D03*
X499500Y154300D03*
Y156500D03*
X501800Y154300D03*
Y156500D03*
X504800Y159800D03*
Y162000D03*
X507100Y159800D03*
Y162000D03*
X451500Y209400D03*
Y211600D03*
X494100Y289600D03*
Y291800D03*
X486250Y285250D03*
Y287450D03*
X466658Y276174D03*
Y278374D03*
X468968Y276174D03*
Y278374D03*
X462553Y275970D03*
Y278170D03*
X474500Y299900D03*
X458700Y298100D03*
X462600Y298200D03*
X454700Y276000D03*
Y278200D03*
X458700Y276000D03*
Y278200D03*
X450000Y276000D03*
Y278200D03*
X458667Y315905D03*
Y318105D03*
X486308Y316042D03*
Y318242D03*
X451100Y315700D03*
Y317900D03*
X474500Y302100D03*
X458700Y300300D03*
X462600Y300400D03*
X515055Y173622D03*
Y175822D03*
X517255Y173622D03*
Y175822D03*
X524700Y173700D03*
X526900D03*
X533093Y220867D03*
Y223067D03*
X530893Y220867D03*
Y223067D03*
X524700Y175900D03*
X526900D03*
X534120Y240257D03*
Y242457D03*
X531920Y240257D03*
Y242457D03*
X512700Y317400D03*
Y319600D03*
X677505Y112037D03*
X667843Y170060D03*
Y172260D03*
X680671Y133232D03*
Y135432D03*
X673887Y133186D03*
Y135386D03*
X677505Y114237D03*
X686636Y133246D03*
Y135446D03*
X671452Y200715D03*
Y202915D03*
X699245Y111675D03*
Y113875D03*
G54D61*
X358550Y319900D03*
X354800D03*
X351050D03*
Y330500D03*
X354800D03*
X358550D03*
X674989Y255684D03*
X678739D03*
X682489D03*
Y245084D03*
X678739D03*
X674989D03*
G54D16*
X45000Y207400D03*
G54D34*
X254300Y369300D03*
X300500Y144300D03*
X301000Y228800D03*
X300500Y186300D03*
X362810Y254940D03*
X362868Y283087D03*
X362677Y310862D03*
X581500Y464800D03*
X676531Y385433D03*
X788107Y128193D03*
G54D43*
X287500Y286300D03*
X358298Y250444D03*
X358342Y278587D03*
X358214Y306662D03*
X409100Y340600D03*
X421500Y341100D03*
X440740Y341244D03*
X435200Y330600D03*
X427500Y330700D03*
X421500Y330800D03*
X396000Y340700D03*
X467900Y350800D03*
X474577Y339465D03*
X496100Y351900D03*
X497206Y341831D03*
X464000Y340800D03*
X460000D03*
X451300Y340900D03*
X491445Y346958D03*
X477400Y350900D03*
X468000Y340800D03*
X486873Y346956D03*
X472000Y350800D03*
X482618Y339442D03*
X513517Y341846D03*
X521522D03*
X517517D03*
X518500Y352300D03*
X522500D03*
X549400Y485990D03*
X631500Y105300D03*
X632300Y154700D03*
X644710Y22867D03*
X637003Y62309D03*
X689468Y246705D03*
X691887Y264477D03*
X657031Y376683D03*
X666031D03*
X661531D03*
X698541Y199189D03*
X785350Y91800D03*
X781000D03*
X802696Y137400D03*
X786500D03*
X790500D03*
X796110Y182900D03*
X792000Y229300D03*
G54D25*
X153458Y418270D03*
X265312Y59618D03*
X622826Y234952D03*
X585300Y449500D03*
X663745Y23414D03*
X670777Y135318D03*
X670718Y141825D03*
X687800Y128700D03*
X680182Y128735D03*
X644723Y144911D03*
X644750Y134900D03*
X644700Y148800D03*
X674692Y195715D03*
X667012Y195705D03*
X658000Y238400D03*
X688112Y480221D03*
X708588Y145327D03*
X701689Y169842D03*
X709210D03*
X729655Y195527D03*
X724904Y329638D03*
G54D35*
X262600Y416700D03*
X301000Y164800D03*
X300500Y204800D03*
Y247300D03*
X362868Y269041D03*
X362689Y297141D03*
X631781Y134308D03*
X639120Y457930D03*
X776500Y114300D03*
X790000Y98300D03*
X776500D03*
G54D44*
X283000Y286300D03*
X316786Y386542D03*
X358169Y265368D03*
X358222Y292641D03*
X413400Y340600D03*
X417400D03*
X449400Y330800D03*
X427500Y340600D03*
X432900Y340900D03*
X445400Y330800D03*
X447300Y340900D03*
X391900Y340700D03*
X450200Y322200D03*
X510000Y351600D03*
X506000D03*
X505379Y341811D03*
X501281D03*
X509517Y341846D03*
X502200Y360609D03*
X455900Y340800D03*
X478618Y339442D03*
X547908Y331732D03*
X541747Y331765D03*
X529947Y331800D03*
X525522Y341846D03*
X529622D03*
X558000Y348300D03*
X554000D03*
X533947Y331800D03*
X540200Y351400D03*
X536200D03*
X545200D03*
X549200D03*
X633000Y62300D03*
X636000Y203300D03*
X632000D03*
X624000D03*
X628000D03*
X618026Y261552D03*
X611526D03*
X659850Y46800D03*
X641003Y62309D03*
X640000Y203300D03*
X648000D03*
X652000D03*
X644000D03*
X656000D03*
X660000D03*
X645500Y261200D03*
X652000D03*
X672131Y383183D03*
X717500Y135250D03*
X713500D03*
X710800Y214600D03*
X719700D03*
X785350Y84300D03*
X794500Y137400D03*
X782500D03*
X798500D03*
X796500Y229300D03*
G54D26*
X148138Y423870D03*
X155738D03*
X172738Y425870D03*
X165138D03*
X172738Y417870D03*
X165138D03*
X148138Y431470D03*
X155738D03*
X248600Y238500D03*
X241000D03*
X248600Y230900D03*
X241000D03*
X248600Y223300D03*
X241000D03*
X248600Y215700D03*
X241000D03*
X248600Y208100D03*
X241000D03*
X255200Y375750D03*
X262800D03*
X281300Y156500D03*
X273700D03*
X281300Y147500D03*
X273700D03*
X281300Y231000D03*
X273700D03*
X281300Y189500D03*
X273700D03*
X281300Y239500D03*
X273700D03*
X281300Y198000D03*
X273700D03*
X522812Y470071D03*
X515212D03*
X523000Y462400D03*
X515400D03*
X617726Y244452D03*
X625326D03*
X610826D03*
X603226D03*
X675462Y162183D03*
X667862D03*
X675597Y177941D03*
X667997D03*
X675735Y187351D03*
X668135D03*
X645800Y244000D03*
X638200D03*
X652700D03*
X660300D03*
X643100Y364900D03*
X650700D03*
X682000Y466700D03*
X689600D03*
X682000Y474366D03*
X689600D03*
X719304Y345038D03*
X726904D03*
X719304Y353038D03*
X726904D03*
X797800Y112500D03*
X790200D03*
X802307Y124593D03*
X794707D03*
G54D62*
X366040Y320965D03*
X368600D03*
X371160D03*
Y329035D03*
X368600D03*
X366040D03*
G54D80*
X739680Y429140D03*
Y438140D03*
G54D71*
X622826Y238652D03*
X619226D03*
X644700Y131100D03*
X641100D03*
X657800Y234700D03*
X654200D03*
X723200Y119500D03*
X719600D03*
G54D53*
X378811Y198292D03*
X381011D03*
X378811Y200592D03*
X381011D03*
X378811Y203792D03*
X381011D03*
X378811Y206092D03*
X381011D03*
X378811Y211592D03*
X381011D03*
X378811Y209292D03*
X381011D03*
X378811Y214792D03*
X381011D03*
X378811Y217092D03*
X381011D03*
X399400Y226400D03*
X401600D03*
X445568Y297155D03*
X447768D03*
X489050Y210650D03*
X491250D03*
X508338Y233748D03*
X510538D03*
X508338Y214971D03*
X510538D03*
X508338Y225790D03*
X510538D03*
X508338Y217456D03*
X510538D03*
X489100Y229900D03*
X491300D03*
X489117Y234208D03*
X491317D03*
X489100Y227400D03*
X491300D03*
X508338Y231089D03*
X510538D03*
X508338Y223290D03*
X510538D03*
X489950Y285450D03*
X492150D03*
X489900Y273650D03*
X492100D03*
X489900Y265600D03*
X492100D03*
X489950Y277500D03*
X492150D03*
X489050Y238200D03*
X491250D03*
X692612Y164865D03*
X694812D03*
X692685Y156336D03*
X694885D03*
X692450Y168950D03*
X694650D03*
X692612Y162665D03*
X694812D03*
X692685Y158536D03*
X694885D03*
X692600Y150050D03*
X694800D03*
X692602Y145815D03*
X694802D03*
X692450Y171150D03*
X694650D03*
X692600Y152250D03*
X694800D03*
X670097Y129076D03*
X672297D03*
X657737Y194808D03*
X659937D03*
X701341Y81023D03*
X703541D03*
X701344Y83270D03*
X703544D03*
X712560Y83760D03*
X714760D03*
X712559Y85992D03*
X714759D03*
X698923Y164914D03*
X701123D03*
X698950Y152240D03*
X701150D03*
X705362Y164913D03*
X707562D03*
X725142Y145165D03*
X727342D03*
X725142Y151175D03*
X727342D03*
X725142Y157715D03*
X727342D03*
X723922Y126891D03*
X726122D03*
X725142Y170065D03*
X727342D03*
X705362Y162713D03*
X707562D03*
X705321Y158619D03*
X707521D03*
X705352Y150035D03*
X707552D03*
X698923Y162714D03*
X701123D03*
X698944Y158543D03*
X701144D03*
X698950Y150040D03*
X701150D03*
X698952Y145865D03*
X701152D03*
X705321Y156419D03*
X707521D03*
X698944Y156343D03*
X701144D03*
X705352Y152235D03*
X707552D03*
X725142Y176315D03*
X727342D03*
X725142Y189185D03*
X727342D03*
X725142Y182795D03*
X727342D03*
G54D17*
X54900Y204700D03*
X49900Y209700D03*
X59900D03*
X54900Y214700D03*
Y209700D03*
X201400Y174400D03*
X192400D03*
X196900D03*
X179800Y133500D03*
X175800Y129500D03*
X179800D03*
X175800Y133500D03*
X192400Y191600D03*
X196900D03*
X201400D03*
X192400Y187300D03*
X196900D03*
X201400D03*
Y178700D03*
X192400Y183000D03*
X196900D03*
X201400D03*
X192400Y178700D03*
X196900D03*
X246493Y399567D03*
X242893D03*
X257020Y390670D03*
X253420D03*
X249820D03*
X246220D03*
X256120Y395170D03*
X243120D03*
X247620D03*
X251870D03*
X242620Y390670D03*
X260893Y399567D03*
X257293D03*
X260620Y390670D03*
Y395170D03*
X253693Y399567D03*
X250093D03*
X609400Y446850D03*
X604400Y456100D03*
Y451850D03*
Y447350D03*
Y460350D03*
X609400Y450450D03*
Y454050D03*
Y457650D03*
Y461250D03*
X599503Y447123D03*
Y450723D03*
Y454323D03*
Y457923D03*
X604400Y464850D03*
X609400D03*
X599503Y461523D03*
Y465123D03*
X694400Y452900D03*
Y457400D03*
Y461900D03*
X689900Y457400D03*
Y452950D03*
X689700Y461850D03*
X698900Y457400D03*
X699000Y452950D03*
X698950Y461800D03*
G54D90*
G01X380500Y173000D02*
X380830Y172670D01*
Y170289D01*
X386478Y161590D01*
X390722Y141623D01*
X379650Y89530D01*
X365986Y68492D01*
X362586Y52478D01*
Y19435D01*
G03X365104Y16917I2518J0D01*
G01X366460D01*
G02X366792Y16779I0J-468D01*
G02X366929Y16448I-331J-331D01*
G01Y14961D01*
G01X382700Y173000D02*
X382430Y172730D01*
Y170763D01*
X387982Y162213D01*
X392358Y141623D01*
X386752Y115245D01*
X381154Y88907D01*
X380353Y87672D01*
X380665Y86206D01*
X379864Y84973D01*
X378398Y84662D01*
X377597Y83429D01*
X377908Y81963D01*
X377108Y80730D01*
X375641Y80418D01*
X374841Y79185D01*
X375152Y77719D01*
X374351Y76486D01*
X372885Y76175D01*
X367490Y67869D01*
X364186Y52310D01*
Y19435D01*
G03X365104Y18517I918J0D01*
G01X366460D01*
G03X366792Y18655I0J468D01*
G03X366929Y18986I-331J331D01*
G01Y20473D01*
G01X386500Y173000D02*
X386838Y172662D01*
Y169890D01*
X391077Y163364D01*
X395928Y140554D01*
X382737Y78496D01*
X372048Y62033D01*
X369673Y50848D01*
Y14710D01*
G03X372191Y12192I2518J0D01*
G01X373547D01*
G02X373879Y12054I0J-468D01*
G02X374016Y11723I-331J-331D01*
G01Y10237D01*
G01X388700Y173000D02*
X388438Y172738D01*
Y170365D01*
X392581Y163987D01*
X397564Y140554D01*
X390898Y109192D01*
X390899D01*
X384240Y77868D01*
X384552Y76402D01*
X383751Y75169D01*
X382285Y74857D01*
X381484Y73625D01*
X381796Y72158D01*
X380995Y70925D01*
X379529Y70614D01*
X378728Y69381D01*
X379040Y67915D01*
X378240Y66682D01*
X376773Y66370D01*
X373552Y61410D01*
X371273Y50679D01*
Y14710D01*
G03X372191Y13792I918J0D01*
G01X373547D01*
G03X373879Y13930I0J468D01*
G03X374016Y14261I-331J331D01*
G01Y15748D01*
G01X392500Y173000D02*
X392844Y172656D01*
Y170793D01*
X393151Y169346D01*
X397051Y163341D01*
X401822Y140881D01*
X387162Y71901D01*
X378113Y57968D01*
X376741Y51515D01*
Y19454D01*
G03X379278Y16917I2537J0D01*
G01X380634D01*
G02X380966Y16779I0J-468D01*
G02X381103Y16448I-331J-331D01*
G01Y14961D01*
G01X394700Y173000D02*
X394444Y172744D01*
Y170961D01*
X394655Y169968D01*
X398555Y163964D01*
X398677Y163387D01*
X398860Y162526D01*
X400118Y161709D01*
X400423Y160272D01*
X399606Y159014D01*
X399912Y157577D01*
X401169Y156760D01*
X401474Y155322D01*
X400658Y154065D01*
X400963Y152627D01*
X402220Y151810D01*
X402526Y150372D01*
X401709Y149115D01*
X403458Y140881D01*
X388666Y71278D01*
X379617Y57345D01*
X378341Y51346D01*
Y19454D01*
G03X379278Y18517I937J0D01*
G01X380634D01*
G03X380966Y18655I0J468D01*
G03X381103Y18986I-331J331D01*
G01Y20473D01*
G01X398500Y173000D02*
X398833Y172667D01*
Y169708D01*
X402533Y166008D01*
X407682Y141777D01*
X392088Y68392D01*
X385952Y58947D01*
X383846Y49042D01*
Y14710D01*
G03X386364Y12192I2518J0D01*
G01X387720D01*
G02X388052Y12054I0J-468D01*
G02X388189Y11723I-331J-331D01*
G01Y10237D01*
G01X400700Y173000D02*
X400433Y172733D01*
Y170371D01*
X404000Y166804D01*
X409318Y141777D01*
X408559Y138203D01*
X407870Y134961D01*
X408686Y133703D01*
X408381Y132265D01*
X407124Y131449D01*
X406818Y130011D01*
X407634Y128753D01*
X407329Y127315D01*
X406072Y126499D01*
X405766Y125061D01*
X406583Y123804D01*
X406277Y122366D01*
X405020Y121550D01*
X393592Y67769D01*
X387456Y58324D01*
X385446Y48873D01*
Y14710D01*
G03X386364Y13792I918J0D01*
G01X387720D01*
G03X388052Y13930I0J468D01*
G03X388189Y14261I-331J331D01*
G01Y15748D01*
G01X378811Y217092D02*
X377369D01*
X376856Y216579D01*
X374233D01*
X366875Y215014D01*
X355585Y207683D01*
X343542Y189136D01*
X335947Y153396D01*
X343848Y116235D01*
X343847D01*
X333844Y69164D01*
Y19831D01*
G03X336758Y16917I2914J0D01*
G01X338114D01*
G02X338446Y16779I0J-468D01*
G02X338583Y16448I-331J-331D01*
G01Y14961D01*
G01Y20473D02*
Y18986D01*
G02X338446Y18655I-468J0D01*
G02X338114Y18517I-332J330D01*
G01X336758D01*
G02X335444Y19831I0J1314D01*
G01Y68992D01*
X345413Y115902D01*
X345414D01*
X345484Y116235D01*
X337583Y153396D01*
X340741Y168257D01*
X341998Y169073D01*
X342304Y170511D01*
X341487Y171768D01*
X341793Y173206D01*
Y173207D01*
X343050Y174023D01*
X343356Y175461D01*
X342539Y176718D01*
X342845Y178156D01*
X344102Y178973D01*
X344408Y180410D01*
X343591Y181668D01*
X343897Y183106D01*
X345154Y183922D01*
X345459Y185360D01*
X344643Y186617D01*
X345046Y188513D01*
X349834Y195887D01*
X351300Y196199D01*
X352101Y197432D01*
X351789Y198898D01*
X352590Y200131D01*
X354056Y200443D01*
X354856Y201676D01*
X354545Y203142D01*
X355624Y204803D01*
Y204804D01*
X356742Y206526D01*
X367498Y213510D01*
X374402Y214979D01*
X377182D01*
X377369Y214792D01*
X378811D01*
G01Y211592D02*
X377419D01*
X376919Y211092D01*
X374547D01*
X371322Y210408D01*
X359468Y202710D01*
X349012Y186609D01*
X342003Y153649D01*
X351018Y111229D01*
X341327Y65635D01*
Y14710D01*
G03X343845Y12192I2518J0D01*
G01X345201D01*
G02X345533Y12054I0J-468D01*
G02X345670Y11723I-331J-331D01*
G01Y10237D01*
G01Y15748D02*
Y14261D01*
G02X345533Y13930I-468J0D01*
G02X345201Y13792I-332J330D01*
G01X343845D01*
G02X342927Y14710I0J918D01*
G01Y65466D01*
X347787Y88330D01*
X349044Y89146D01*
X349349Y90584D01*
X348533Y91841D01*
X348839Y93279D01*
X350096Y94096D01*
X350402Y95534D01*
X349585Y96791D01*
X349891Y98229D01*
X351148Y99045D01*
X351454Y100483D01*
X350637Y101740D01*
X350943Y103178D01*
X352200Y103995D01*
X352506Y105432D01*
X351689Y106690D01*
X352654Y111229D01*
X343639Y153649D01*
X343945Y155087D01*
X345202Y155903D01*
X345508Y157341D01*
X344692Y158598D01*
X344997Y160036D01*
X346255Y160852D01*
X346560Y162290D01*
X345744Y163548D01*
X350516Y185986D01*
X360625Y201553D01*
X371944Y208904D01*
X374715Y209492D01*
X377119D01*
X377319Y209292D01*
X378811D01*
G01X352756Y14961D02*
Y16448D01*
G03X352619Y16779I-468J0D01*
G03X352287Y16917I-332J-330D01*
G01X350635D01*
G02X348413Y19139I0J2222D01*
G01Y63620D01*
X358199Y109662D01*
X348905Y153386D01*
X349899Y158071D01*
X352360Y161859D01*
X358333Y189934D01*
X358332D01*
X358394Y190225D01*
X364144Y199064D01*
X364145Y199063D01*
X364817Y200098D01*
X373278Y205592D01*
X376919D01*
X377419Y206092D01*
X378811D01*
G01X352756Y20473D02*
Y18986D01*
G02X352619Y18655I-468J0D01*
G02X352287Y18517I-332J330D01*
G01X350635D01*
G02X350013Y19139I0J622D01*
G01Y63451D01*
X354399Y84085D01*
X355656Y84902D01*
X355962Y86339D01*
X355145Y87597D01*
X355451Y89035D01*
X356708Y89851D01*
X357014Y91289D01*
X356197Y92546D01*
X356503Y93984D01*
X357760Y94800D01*
X358066Y96238D01*
X357249Y97495D01*
X357555Y98933D01*
X358812Y99750D01*
X359118Y101188D01*
X358301Y102445D01*
X359835Y109662D01*
X350541Y153386D01*
X351403Y157448D01*
X353864Y161236D01*
X359898Y189601D01*
X360769Y190940D01*
X362235Y191250D01*
X363037Y192482D01*
X362726Y193949D01*
X363528Y195181D01*
X364995Y195491D01*
X365797Y196723D01*
X365486Y198190D01*
X365974Y198940D01*
X373752Y203992D01*
X377119D01*
X377319Y203792D01*
X378811D01*
G01Y200592D02*
X377701D01*
X377170Y200061D01*
X375279D01*
X373874Y198656D01*
Y196295D01*
X360776Y176109D01*
X356100Y154098D01*
X365317Y110699D01*
X355500Y64512D01*
Y14710D01*
G03X358018Y12192I2518J0D01*
G01X359374D01*
G02X359706Y12054I0J-468D01*
G02X359843Y11723I-331J-331D01*
G01Y10237D01*
G01X378811Y198292D02*
X377369D01*
X377200Y198461D01*
X375942D01*
X375474Y197993D01*
Y195821D01*
X374411Y194183D01*
X373607Y192944D01*
X371997Y190462D01*
X372309Y188996D01*
X371509Y187763D01*
X370043Y187450D01*
X369243Y186217D01*
X369555Y184751D01*
X368755Y183518D01*
X367289Y183205D01*
X364784Y179345D01*
X362280Y175486D01*
X357736Y154098D01*
X366953Y110699D01*
X365966Y106056D01*
X366783Y104799D01*
X366477Y103361D01*
X365220Y102544D01*
X364914Y101106D01*
X365731Y99849D01*
X365425Y98411D01*
X364168Y97595D01*
X363862Y96157D01*
X364679Y94900D01*
X364373Y93462D01*
X363116Y92646D01*
X362810Y91208D01*
X363627Y89950D01*
X363321Y88513D01*
X362064Y87696D01*
X357100Y64343D01*
Y14710D01*
G03X358018Y13792I918J0D01*
G01X359374D01*
G03X359706Y13930I0J468D01*
G03X359843Y14261I-331J331D01*
G01Y15748D01*
G01X380500Y175200D02*
Y176000D01*
X380893Y176393D01*
Y191420D01*
X388999Y199526D01*
X391424D01*
G01X382700Y175200D02*
Y176100D01*
X382493Y176307D01*
Y178024D01*
X383553Y179084D01*
Y180554D01*
X382493Y181614D01*
Y183084D01*
X383553Y184144D01*
Y185614D01*
X382493Y186674D01*
Y190757D01*
X383439Y191703D01*
X384939D01*
X385978Y192743D01*
Y194242D01*
X389662Y197926D01*
X391424D01*
G01X386500Y175200D02*
Y176692D01*
X386754Y176946D01*
Y189845D01*
X391825Y194916D01*
X398524D01*
X402190Y198582D01*
G01X389764Y216536D02*
Y215894D01*
G02X389238Y215368I-526J0D01*
G01X387227D01*
X385860Y216735D01*
X382810D01*
X382453Y217092D01*
X381011D01*
G01X389764Y212599D02*
Y213242D01*
G03X389238Y213768I-526J0D01*
G01X386564D01*
X385197Y215135D01*
X382796D01*
X382453Y214792D01*
X381011D01*
G01Y211592D02*
X382453D01*
X382906Y211139D01*
X383648D01*
X383940Y211431D01*
X388424D01*
G01X381011Y209292D02*
X382453D01*
X382700Y209539D01*
X384311D01*
X384603Y209831D01*
X388424D01*
G01X381011Y206092D02*
X382453D01*
X382903Y205642D01*
X383801D01*
X385722Y207563D01*
X387893D01*
G01Y205963D02*
X386385D01*
X384464Y204042D01*
X382703D01*
X382453Y203792D01*
X381011D01*
G01Y200592D02*
X382453D01*
X382803Y200242D01*
X383753D01*
X387154Y203643D01*
X388433D01*
G01X381011Y198292D02*
X382453D01*
X382803Y198642D01*
X384416D01*
X387817Y202043D01*
X388433D01*
G01X404500Y173000D02*
X404831Y172669D01*
Y170509D01*
X407453Y167887D01*
X413397Y139905D01*
X397617Y65651D01*
X391712Y56558D01*
X390933Y52893D01*
Y19435D01*
G03X393451Y16917I2518J0D01*
G01X394807D01*
G02X395139Y16779I0J-468D01*
G02X395276Y16448I-331J-331D01*
G01Y14961D01*
G01X406700Y173000D02*
X406431Y172731D01*
Y171172D01*
X408920Y168683D01*
X415033Y139905D01*
X414117Y135594D01*
X414118D01*
X413272Y131616D01*
X414088Y130359D01*
X413782Y128921D01*
X412525Y128104D01*
X412220Y126666D01*
X413036Y125409D01*
X412731Y123971D01*
X411474Y123155D01*
X411168Y121717D01*
X411985Y120460D01*
X411679Y119022D01*
X410422Y118205D01*
X399121Y65028D01*
X393216Y55935D01*
X392533Y52724D01*
Y19435D01*
G03X393451Y18517I918J0D01*
G01X394807D01*
G03X395139Y18655I0J468D01*
G03X395276Y18986I-331J331D01*
G01Y20473D01*
G01X402363Y10237D02*
Y11723D01*
G03X402226Y12054I-468J0D01*
G03X401894Y12192I-332J-330D01*
G01X400538D01*
G02X398020Y14710I0J2518D01*
G01Y49026D01*
X399363Y55347D01*
X402509Y60192D01*
X418937Y137478D01*
X412002Y170134D01*
X410850Y171286D01*
Y172650D01*
X410500Y173000D01*
G01X402363Y15748D02*
Y14261D01*
G02X402226Y13930I-468J0D01*
G02X401894Y13792I-332J330D01*
G01X400538D01*
G02X399620Y14710I0J918D01*
G01Y48857D01*
X400867Y54724D01*
X404013Y59569D01*
X417013Y120730D01*
X418270Y121547D01*
X418576Y122985D01*
X417760Y124242D01*
X418065Y125680D01*
X419322Y126496D01*
X419628Y127934D01*
X418812Y129191D01*
X419117Y130629D01*
X420374Y131446D01*
X420680Y132884D01*
X419864Y134141D01*
X420573Y137478D01*
X413469Y170930D01*
X412450Y171949D01*
Y172750D01*
X412700Y173000D01*
G01X416500D02*
Y172492D01*
X416800Y172192D01*
Y170805D01*
X417676Y169929D01*
X424810Y136360D01*
X424421Y134527D01*
X424420Y134525D01*
X414991Y90166D01*
X408412Y59215D01*
X405947Y55421D01*
X405886Y55126D01*
X405512Y53318D01*
X405106Y51351D01*
Y19435D01*
G03X407624Y16917I2518J0D01*
G01X408980D01*
G02X409312Y16779I0J-468D01*
G02X409449Y16448I-331J-331D01*
G01Y14961D01*
G01X418700Y173000D02*
Y172557D01*
X418400Y172257D01*
Y171468D01*
X419143Y170725D01*
X426446Y136360D01*
X425986Y134194D01*
X426802Y132937D01*
X426497Y131499D01*
X425240Y130683D01*
X424934Y129245D01*
X425750Y127988D01*
X425445Y126550D01*
X424188Y125734D01*
X423882Y124296D01*
X424698Y123038D01*
X424393Y121600D01*
X423136Y120784D01*
X409916Y58592D01*
X407453Y54802D01*
X406706Y51187D01*
Y19435D01*
G03X407624Y18517I918J0D01*
G01X408980D01*
G03X409312Y18655I0J468D01*
G03X409449Y18986I-331J331D01*
G01Y20473D01*
G01X422500Y173000D02*
X422846Y172654D01*
Y168695D01*
X430303Y133603D01*
X412193Y48434D01*
Y14710D01*
G03X414711Y12192I2518J0D01*
G01X416067D01*
G02X416399Y12054I0J-468D01*
G02X416536Y11723I-331J-331D01*
G01Y10237D01*
G01Y15748D02*
Y14261D01*
G02X416399Y13930I-468J0D01*
G02X416067Y13792I-332J330D01*
G01X414711D01*
G02X413793Y14710I0J918D01*
G01Y48265D01*
X427866Y114446D01*
X429123Y115262D01*
X429429Y116700D01*
X428612Y117957D01*
X428918Y119395D01*
X430175Y120211D01*
X430481Y121649D01*
X429665Y122907D01*
X429971Y124345D01*
X431228Y125161D01*
X431534Y126599D01*
X430717Y127856D01*
X431939Y133602D01*
X424446Y168864D01*
Y172746D01*
X424700Y173000D01*
G01X428500D02*
X428757Y172743D01*
Y165003D01*
X435885Y131470D01*
X419279Y53314D01*
Y19435D01*
G03X421797Y16917I2518J0D01*
G01X423153D01*
G02X423485Y16779I0J-468D01*
G02X423622Y16448I-331J-331D01*
G01Y14961D01*
G01X430700Y173000D02*
X430357Y172657D01*
Y165171D01*
X430358D01*
X437521Y131470D01*
X436310Y125769D01*
X437126Y124511D01*
X436821Y123073D01*
X435564Y122257D01*
X435258Y120819D01*
X436074Y119561D01*
X435769Y118123D01*
X434512Y117307D01*
X434206Y115869D01*
X435023Y114611D01*
X434717Y113174D01*
X433460Y112357D01*
X420879Y53145D01*
Y19435D01*
G03X421797Y18517I918J0D01*
G01X423153D01*
G03X423485Y18655I0J468D01*
G03X423622Y18986I-331J331D01*
G01Y20473D01*
G01X434500Y173000D02*
X434752Y172748D01*
Y163992D01*
X442066Y129585D01*
X426366Y55706D01*
Y14710D01*
G03X428884Y12192I2518J0D01*
G01X430240D01*
G02X430572Y12054I0J-468D01*
G02X430709Y11723I-331J-331D01*
G01Y10237D01*
G01X436700Y173000D02*
X436352Y172652D01*
Y164161D01*
X443702Y129585D01*
X442862Y125632D01*
X442860Y125622D01*
X443676Y124365D01*
X443371Y122927D01*
X442114Y122110D01*
X441808Y120673D01*
X442625Y119415D01*
X442319Y117978D01*
X441062Y117161D01*
X440756Y115723D01*
X441573Y114466D01*
X441267Y113028D01*
X440010Y112212D01*
X427966Y55537D01*
Y14710D01*
G03X428884Y13792I918J0D01*
G01X430240D01*
G03X430572Y13930I0J468D01*
G03X430709Y14261I-331J331D01*
G01Y15748D01*
G01X440500Y173000D02*
X440788Y172712D01*
Y159847D01*
X447649Y127565D01*
X433453Y60775D01*
Y19435D01*
G03X435971Y16917I2518J0D01*
G01X437327D01*
G02X437659Y16779I0J-468D01*
G02X437796Y16448I-331J-331D01*
G01Y14961D01*
G01Y20473D02*
Y18986D01*
G02X437659Y18655I-468J0D01*
G02X437327Y18517I-332J330D01*
G01X435971D01*
G02X435053Y19435I0J918D01*
G01Y60606D01*
X445861Y111455D01*
X447118Y112271D01*
X447424Y113709D01*
X446607Y114966D01*
X446913Y116404D01*
X448170Y117220D01*
X448476Y118658D01*
X447659Y119915D01*
X447965Y121353D01*
X449222Y122169D01*
X449528Y123607D01*
X448711Y124864D01*
X449285Y127564D01*
X442388Y160016D01*
Y172688D01*
X442700Y173000D01*
G01X446500D02*
X446751Y172749D01*
Y155366D01*
X453302Y124541D01*
X452852Y122423D01*
Y122424D01*
X440539Y64491D01*
Y14710D01*
G03X443057Y12192I2518J0D01*
G01X444413D01*
G02X444745Y12054I0J-468D01*
G02X444882Y11723I-331J-331D01*
G01Y10237D01*
G01X448700Y173000D02*
X448351Y172651D01*
Y155535D01*
X454938Y124541D01*
X454417Y122090D01*
X455234Y120833D01*
X454928Y119395D01*
X453671Y118578D01*
X453365Y117140D01*
X454182Y115883D01*
X453876Y114445D01*
X452619Y113629D01*
X452313Y112191D01*
X453130Y110934D01*
X452824Y109496D01*
X451567Y108679D01*
X442139Y64322D01*
Y14710D01*
G03X443057Y13792I918J0D01*
G01X444413D01*
G03X444745Y13930I0J468D01*
G03X444882Y14261I-331J331D01*
G01Y15748D01*
G01X452500Y173000D02*
X452769Y172731D01*
Y155907D01*
X459366Y124870D01*
X447626Y69615D01*
Y19435D01*
G03X450144Y16917I2518J0D01*
G01X451500D01*
G02X451832Y16779I0J-468D01*
G02X451969Y16448I-331J-331D01*
G01Y14961D01*
G01X388700Y175200D02*
Y176692D01*
X388354Y177038D01*
Y179085D01*
X389414Y180145D01*
Y181615D01*
X388354Y182675D01*
Y184145D01*
X389414Y185205D01*
Y186675D01*
X388354Y187735D01*
Y189182D01*
X392488Y193316D01*
X399187D01*
X403355Y197484D01*
G01X392500Y175200D02*
Y176100D01*
X392749Y176349D01*
Y188946D01*
X394823Y191020D01*
X399077D01*
X405992Y197935D01*
G01X394700Y175200D02*
Y176128D01*
X394349Y176479D01*
Y177996D01*
X395459Y179106D01*
Y180576D01*
X394349Y181686D01*
Y183156D01*
X395459Y184266D01*
Y185736D01*
X394349Y186846D01*
Y188283D01*
X395486Y189420D01*
X399740D01*
X407124Y196804D01*
G01X398500Y175200D02*
Y176374D01*
X398663Y176537D01*
Y186204D01*
X410729Y198270D01*
Y198786D01*
G01X400700Y175200D02*
Y176364D01*
X400263Y176801D01*
Y180442D01*
X401323Y181502D01*
Y182972D01*
X400263Y184032D01*
Y185541D01*
X412329Y197607D01*
Y198786D01*
G01X404500Y175200D02*
Y176100D01*
X404753Y176353D01*
Y186483D01*
X414753Y196483D01*
Y198248D01*
G01X406700Y175200D02*
Y176100D01*
X406353Y176447D01*
Y180803D01*
X407413Y181863D01*
Y183333D01*
X406353Y184393D01*
Y185820D01*
X416353Y195820D01*
Y198248D01*
G01X410500Y175200D02*
Y176192D01*
X410685Y176377D01*
Y187210D01*
X422557Y199082D01*
Y199567D01*
G01X412700Y175200D02*
Y176192D01*
X412285Y176607D01*
Y180938D01*
X413345Y181998D01*
Y183468D01*
X412285Y184528D01*
Y186547D01*
X424157Y198419D01*
Y199493D01*
G01X416500Y175200D02*
Y176600D01*
X416684Y176784D01*
Y188621D01*
X426511Y198448D01*
Y199344D01*
G01X428111D02*
Y197785D01*
X418284Y187958D01*
Y182443D01*
X419344Y181383D01*
Y179913D01*
X418284Y178853D01*
Y177131D01*
X418700Y176715D01*
Y175200D01*
G01X430455Y199262D02*
Y196724D01*
X422661Y188930D01*
Y176853D01*
X422500Y176692D01*
Y175200D01*
G01X432055Y199262D02*
Y196061D01*
X424261Y188267D01*
Y182282D01*
X425321Y181222D01*
Y179752D01*
X424261Y178692D01*
Y177131D01*
X424700Y176692D01*
Y175200D01*
G01X437063Y197031D02*
Y195405D01*
X428738Y187080D01*
Y176930D01*
X428500Y176692D01*
Y175200D01*
G01X438663Y197031D02*
Y194742D01*
X430338Y186417D01*
Y182237D01*
X431398Y181177D01*
Y179707D01*
X430338Y178647D01*
Y177054D01*
X430700Y176692D01*
Y175200D01*
G01X441713Y197031D02*
Y193255D01*
X434707Y186249D01*
Y176899D01*
X434500Y176692D01*
Y175200D01*
G01X443313Y197031D02*
Y192592D01*
X436307Y185586D01*
Y182052D01*
X437367Y180992D01*
Y179522D01*
X436307Y178462D01*
Y177085D01*
X436700Y176692D01*
Y175200D01*
G01X446058Y198654D02*
Y190732D01*
X440707Y185381D01*
Y176899D01*
X440500Y176692D01*
Y175200D01*
G01X447658Y198654D02*
Y190069D01*
X442307Y184718D01*
Y182052D01*
X443367Y180992D01*
Y179522D01*
X442307Y178462D01*
Y177085D01*
X442700Y176692D01*
Y175200D01*
G01X451625Y200185D02*
Y189516D01*
X446770Y184661D01*
Y176270D01*
X446500Y176000D01*
Y175200D01*
G01X453225Y200185D02*
Y188853D01*
X448370Y183998D01*
Y181252D01*
X449430Y180192D01*
Y178722D01*
X448370Y177662D01*
Y176430D01*
X448700Y176100D01*
Y175200D01*
G01X537400Y313400D02*
X538892D01*
X539192Y313100D01*
X554038D01*
X556520Y313629D01*
X562140Y319249D01*
X565074Y323766D01*
X565073D01*
X565076Y323770D01*
X567353Y334491D01*
X566537Y335748D01*
X566842Y337186D01*
X568099Y338003D01*
X569857Y346279D01*
X566954Y359945D01*
X555293Y377898D01*
X477282Y428563D01*
X446488Y435108D01*
X429825D01*
X427857Y433140D01*
X416130D01*
X414486Y433489D01*
X412988Y434462D01*
X412169Y435723D01*
X411896Y437011D01*
X412143Y438173D01*
X413148Y439728D01*
X413404Y439985D01*
G02X413845Y440322I1478J-1478D01*
G01X413870Y440335D01*
X414014Y440413D01*
X414018Y440415D01*
X414025Y440419D01*
X414029Y440421D01*
X414034Y440424D01*
X414041Y440428D01*
X414053Y440434D01*
X414054D01*
G03X414254Y441098I-232J432D01*
G01X413386Y442717D01*
G01X537400Y311200D02*
X538892D01*
X539192Y311500D01*
X554207D01*
X557317Y312162D01*
X563390Y318236D01*
X566580Y323147D01*
X571493Y346279D01*
X568458Y360568D01*
X556450Y379055D01*
X477905Y430068D01*
X446657Y436708D01*
X429162D01*
X427194Y434740D01*
X416298D01*
X415109Y434993D01*
X414145Y435619D01*
X413673Y436345D01*
X413532Y437011D01*
X413647Y437552D01*
X414394Y438708D01*
X414537Y438855D01*
G02X414630Y438926I341J-351D01*
G01X414775Y439004D01*
X414787Y439010D01*
X414793Y439014D01*
X414805Y439020D01*
X414808Y439022D01*
G02X415472Y438822I232J-432D01*
G01X416339Y437205D01*
G01X537500Y319400D02*
X538992D01*
X539292Y319100D01*
X551645D01*
X554483Y319703D01*
X556802Y321210D01*
X559378Y325175D01*
X559892Y327594D01*
X559076Y328851D01*
X559382Y330289D01*
X560639Y331106D01*
X564188Y347791D01*
X561856Y358774D01*
X561853Y358778D01*
X551644Y374496D01*
X477141Y422880D01*
X442718Y430199D01*
X409673D01*
X407195Y430726D01*
X404322Y432591D01*
X403288Y434184D01*
X402826Y436372D01*
X403169Y438007D01*
X404288Y439726D01*
X404546Y439985D01*
G02X404987Y440322I1478J-1478D01*
G01X405012Y440335D01*
X405156Y440413D01*
X405160Y440415D01*
X405167Y440419D01*
X405171Y440421D01*
X405176Y440424D01*
X405183Y440428D01*
X405195Y440434D01*
X405196D01*
G03X405396Y441098I-232J432D01*
G01X404528Y442717D01*
G01X537500Y317200D02*
X538992D01*
X539292Y317500D01*
X551814D01*
X555106Y318199D01*
X557959Y320053D01*
X560883Y324554D01*
X565824Y347791D01*
X563359Y359401D01*
X563357D01*
X552801Y375653D01*
X477764Y424384D01*
X442887Y431799D01*
X409842D01*
X407817Y432230D01*
X405479Y433748D01*
X404792Y434806D01*
X404462Y436373D01*
X404674Y437385D01*
X405538Y438713D01*
X405680Y438855D01*
G02X405772Y438926I343J-349D01*
G01X405917Y439004D01*
X405929Y439010D01*
X405935Y439014D01*
X405947Y439020D01*
X405950Y439022D01*
G02X406614Y438822I232J-432D01*
G01X407480Y437205D01*
G01X537200Y299800D02*
X538692D01*
X538992Y299500D01*
X554381D01*
X556433Y299936D01*
X566841Y306699D01*
X577472Y323067D01*
X579444Y332349D01*
X578627Y333606D01*
X578933Y335044D01*
X580190Y335860D01*
X581643Y342699D01*
X577657Y361466D01*
X562502Y384807D01*
X479663Y438604D01*
X434807Y448138D01*
X415951D01*
X414486Y448449D01*
X413336Y449196D01*
X412247Y450880D01*
X411990Y452083D01*
X412254Y453323D01*
X413114Y454654D01*
X413404Y454945D01*
G02X413845Y455282I1478J-1478D01*
G01X413870Y455295D01*
X414014Y455373D01*
X414018Y455375D01*
X414025Y455379D01*
X414029Y455381D01*
X414034Y455384D01*
X414041Y455388D01*
X414053Y455394D01*
X414054D01*
G03X414254Y456058I-232J432D01*
G01X413386Y457677D01*
G01X537200Y297600D02*
X538692D01*
X538992Y297900D01*
X554550D01*
X557056Y298432D01*
X567998Y305542D01*
X573499Y314011D01*
X578976Y322444D01*
X583279Y342699D01*
X579161Y362089D01*
X563659Y385964D01*
X480286Y440109D01*
X434976Y449738D01*
X416119D01*
X415109Y449953D01*
X414494Y450352D01*
X413751Y451502D01*
X413627Y452084D01*
X413758Y452700D01*
X414361Y453634D01*
X414537Y453815D01*
G02X414630Y453886I341J-351D01*
G01X414775Y453964D01*
X414787Y453970D01*
X414793Y453974D01*
X414805Y453980D01*
X414808Y453982D01*
G02X415472Y453782I232J-432D01*
G01X416339Y452165D01*
G01X537300Y307300D02*
X538792D01*
X539092Y307000D01*
X554801D01*
X557150Y307500D01*
X564620Y312351D01*
X571000Y322177D01*
X571598Y324991D01*
X570782Y326248D01*
X571087Y327686D01*
X572344Y328502D01*
X576015Y345771D01*
X573077Y359595D01*
X559018Y381247D01*
X478230Y433710D01*
X424517Y445126D01*
X409828D01*
X407195Y445686D01*
X404487Y447443D01*
X403299Y449274D01*
X402898Y451163D01*
X403327Y453197D01*
X404310Y454708D01*
X404546Y454945D01*
G02X404987Y455282I1478J-1478D01*
G01X405012Y455295D01*
X405156Y455373D01*
X405160Y455375D01*
X405167Y455379D01*
X405171Y455381D01*
X405176Y455384D01*
X405183Y455388D01*
X405195Y455394D01*
X405196D01*
G03X405396Y456058I-232J432D01*
G01X404528Y457677D01*
G01X537300Y305100D02*
X538792D01*
X539092Y305400D01*
X554970D01*
X557774Y305996D01*
X565777Y311194D01*
X572504Y321554D01*
X577651Y345771D01*
X574581Y360218D01*
X560175Y382404D01*
X478852Y435215D01*
X424686Y446726D01*
X409997D01*
X407818Y447190D01*
X405644Y448600D01*
X404803Y449896D01*
X404534Y451164D01*
X404831Y452574D01*
X405558Y453692D01*
X405678Y453814D01*
G02X405772Y453886I342J-350D01*
G01X405917Y453964D01*
X405929Y453970D01*
X405935Y453974D01*
X405947Y453980D01*
X405950Y453982D01*
G02X406614Y453782I232J-432D01*
G01X407480Y452165D01*
G01X508662Y14961D02*
Y16448D01*
G03X508525Y16779I-468J0D01*
G03X508193Y16917I-332J-330D01*
G01X506837D01*
G02X504319Y19435I0J2518D01*
G01Y63450D01*
X511728Y98310D01*
X504920Y130453D01*
X507872Y144339D01*
X505178Y157011D01*
Y159422D01*
X504800Y159800D01*
G01X508662Y20473D02*
Y18986D01*
G02X508525Y18655I-468J0D01*
G02X508193Y18517I-332J330D01*
G01X506837D01*
G02X505919Y19435I0J918D01*
G01Y63281D01*
X510189Y83372D01*
X511446Y84188D01*
X511752Y85626D01*
X510936Y86883D01*
X511241Y88321D01*
X512498Y89138D01*
X512804Y90576D01*
X511988Y91833D01*
X512293Y93271D01*
X513550Y94087D01*
X513856Y95525D01*
X513039Y96782D01*
X513364Y98309D01*
X506556Y130452D01*
X509508Y144339D01*
X506778Y157180D01*
Y159478D01*
X507100Y159800D01*
G01X454700Y173000D02*
X454369Y172669D01*
Y156076D01*
X461002Y124870D01*
X459842Y119411D01*
X460659Y118154D01*
X460353Y116716D01*
X459096Y115900D01*
X458791Y114462D01*
X459607Y113205D01*
X459302Y111767D01*
X458045Y110950D01*
X457739Y109512D01*
X458556Y108255D01*
X458250Y106817D01*
X456993Y106001D01*
X449226Y69446D01*
Y19435D01*
G03X450144Y18517I918J0D01*
G01X451500D01*
G03X451832Y18655I0J468D01*
G03X451969Y18986I-331J331D01*
G01Y20473D01*
G01X458500Y173000D02*
X458742Y172758D01*
Y155846D01*
X465273Y122221D01*
X454712Y70506D01*
Y14710D01*
G03X457230Y12192I2518J0D01*
G01X458586D01*
G02X458918Y12054I0J-468D01*
G02X459055Y11723I-331J-331D01*
G01Y10237D01*
G01X460700Y173000D02*
X460342Y172642D01*
Y156000D01*
X466905Y122213D01*
X465875Y117171D01*
X466702Y115920D01*
X466408Y114480D01*
X465157Y113653D01*
X464863Y112213D01*
X465689Y110962D01*
X465395Y109522D01*
X464144Y108695D01*
X463850Y107255D01*
X464676Y106004D01*
X464382Y104564D01*
X463132Y103737D01*
X456312Y70344D01*
Y14710D01*
G03X457230Y13792I918J0D01*
G01X458586D01*
G03X458918Y13930I0J468D01*
G03X459055Y14261I-331J331D01*
G01Y15748D01*
G01X464500Y173000D02*
X464856Y172644D01*
Y152429D01*
X471914Y119226D01*
X461799Y71563D01*
Y19435D01*
G03X464317Y16917I2518J0D01*
G01X465673D01*
G02X466005Y16779I0J-468D01*
G02X466142Y16448I-331J-331D01*
G01Y14961D01*
G01X466700Y173000D02*
X466456Y172756D01*
Y152598D01*
X473550Y119227D01*
X473155Y117365D01*
X473972Y116108D01*
X473666Y114670D01*
X472410Y113853D01*
X472105Y112415D01*
X472922Y111158D01*
X472616Y109720D01*
X471360Y108903D01*
X471055Y107465D01*
X471872Y106208D01*
X471566Y104770D01*
X470309Y103953D01*
X463399Y71395D01*
Y19435D01*
G03X464317Y18517I918J0D01*
G01X465673D01*
G03X466005Y18655I0J468D01*
G03X466142Y18986I-331J331D01*
G01Y20473D01*
G01X473229Y10237D02*
Y11723D01*
G03X473092Y12054I-468J0D01*
G03X472760Y12192I-332J-330D01*
G01X471404D01*
G02X468886Y14710I0J2518D01*
G01Y48434D01*
X468890Y66901D01*
Y66906D01*
X468885Y66911D01*
X478858Y113834D01*
X470800Y151886D01*
Y172700D01*
X470500Y173000D01*
G01X473229Y15748D02*
Y14261D01*
G02X473092Y13930I-468J0D01*
G02X472760Y13792I-332J330D01*
G01X471404D01*
G02X470486Y14710I0J918D01*
G01Y48433D01*
X470490Y66766D01*
X477331Y98953D01*
X478589Y99769D01*
X478894Y101207D01*
X478078Y102464D01*
X478383Y103902D01*
X479641Y104719D01*
X479946Y106157D01*
X479130Y107414D01*
X479435Y108852D01*
X480692Y109668D01*
X480998Y111106D01*
X480182Y112363D01*
X480494Y113833D01*
X472400Y152054D01*
Y172700D01*
X472700Y173000D01*
G01X480315Y14961D02*
Y16448D01*
G03X480178Y16779I-468J0D01*
G03X479846Y16917I-332J-330D01*
G01X478490D01*
G02X475972Y19435I0J2518D01*
G01Y65936D01*
X485550Y111001D01*
X478450Y144543D01*
Y153950D01*
X478100Y154300D01*
G01X480315Y20473D02*
Y18986D01*
G02X480178Y18655I-468J0D01*
G02X479846Y18517I-332J330D01*
G01X478490D01*
G02X477572Y19435I0J918D01*
G01Y65767D01*
X483763Y94894D01*
X485020Y95711D01*
X485326Y97149D01*
X484509Y98406D01*
X484815Y99844D01*
X486072Y100660D01*
X486378Y102098D01*
X485561Y103355D01*
X485867Y104793D01*
X487124Y105610D01*
X487430Y107048D01*
X486613Y108305D01*
X487186Y111000D01*
X480050Y144711D01*
Y153950D01*
X480400Y154300D01*
G01X487402Y10237D02*
Y11723D01*
G03X487265Y12054I-468J0D01*
G03X486933Y12192I-332J-330D01*
G01X485577D01*
G02X483059Y14710I0J2518D01*
G01Y57907D01*
X492974Y104563D01*
X485470Y140010D01*
Y153930D01*
X485100Y154300D01*
G01X487402Y15748D02*
Y14261D01*
G02X487265Y13930I-468J0D01*
G02X486933Y13792I-332J330D01*
G01X485577D01*
G02X484659Y14710I0J918D01*
G01Y57738D01*
X491368Y89306D01*
X492625Y90123D01*
X492931Y91561D01*
X492114Y92818D01*
X492420Y94256D01*
X493677Y95072D01*
X493983Y96510D01*
X493166Y97767D01*
X493472Y99205D01*
X494729Y100022D01*
X495034Y101460D01*
X494218Y102717D01*
X494610Y104562D01*
X487070Y140178D01*
Y153970D01*
X487400Y154300D01*
G01X494489Y14961D02*
Y16448D01*
G03X494352Y16779I-468J0D01*
G03X494020Y16917I-332J-330D01*
G01X492664D01*
G02X490146Y19435I0J2518D01*
G01Y58653D01*
X499532Y102786D01*
X492499Y136004D01*
Y153901D01*
X492100Y154300D01*
G01X494489Y20473D02*
Y18986D01*
G02X494352Y18655I-468J0D01*
G02X494020Y18517I-332J330D01*
G01X492664D01*
G02X491746Y19435I0J918D01*
G01Y58484D01*
X498011Y87937D01*
X498012Y87938D01*
X499269Y88754D01*
X499575Y90192D01*
X498758Y91449D01*
X499064Y92887D01*
X500321Y93703D01*
X500627Y95141D01*
X499810Y96398D01*
X500116Y97836D01*
X501373Y98652D01*
X501679Y100090D01*
X500862Y101347D01*
X501168Y102785D01*
X494099Y136172D01*
Y153999D01*
X494400Y154300D01*
G01X499500D02*
X499842Y153958D01*
Y128940D01*
X505554Y101977D01*
X497232Y62840D01*
Y14710D01*
G03X499750Y12192I2518J0D01*
G01X501106D01*
G02X501438Y12054I0J-468D01*
G02X501575Y11723I-331J-331D01*
G01Y10237D01*
G01X501800Y154300D02*
X501442Y153942D01*
Y129108D01*
X507190Y101976D01*
X506884Y100538D01*
X507701Y99281D01*
X507395Y97843D01*
X506138Y97027D01*
X505832Y95589D01*
X506649Y94332D01*
X506343Y92894D01*
X505086Y92078D01*
X504780Y90640D01*
X505597Y89383D01*
X505291Y87945D01*
X504033Y87129D01*
X498832Y62671D01*
Y14710D01*
G03X499750Y13792I918J0D01*
G01X501106D01*
G03X501438Y13930I0J468D01*
G03X501575Y14261I-331J331D01*
G01Y15748D01*
G01X515748Y10237D02*
Y11723D01*
G03X515611Y12054I-468J0D01*
G03X515279Y12192I-332J-330D01*
G01X513923D01*
G02X511405Y14710I0J2518D01*
G01Y58896D01*
X513372Y68160D01*
X514967Y75665D01*
X518390Y91775D01*
X510197Y130331D01*
X517055Y162598D01*
X515300Y170856D01*
Y173377D01*
X515055Y173622D01*
G01X504800Y162000D02*
Y163153D01*
X505251Y163604D01*
Y171025D01*
X503060Y181336D01*
X504861Y189813D01*
X507625Y194073D01*
X513017Y197574D01*
X518362Y205803D01*
X518627Y207052D01*
X519915Y213106D01*
X518651Y219057D01*
X517291Y221209D01*
X513700Y224800D01*
Y233300D01*
G01X507100Y162000D02*
Y163336D01*
X506851Y163585D01*
Y171194D01*
X504696Y181336D01*
X506365Y189190D01*
X508783Y192916D01*
X514174Y196417D01*
X519866Y205180D01*
X520352Y207466D01*
X520353Y207467D01*
X520352D01*
X521551Y213106D01*
X520157Y219670D01*
X518549Y222215D01*
X515300Y225463D01*
Y233300D01*
G01X457953Y198809D02*
Y198159D01*
X456022Y196228D01*
Y187132D01*
X452800Y183910D01*
Y176300D01*
X452500Y176000D01*
Y175200D01*
G01X459553Y198809D02*
Y197496D01*
X457622Y195565D01*
Y186469D01*
X454400Y183247D01*
Y181289D01*
X455460Y180229D01*
Y178759D01*
X454400Y177699D01*
Y176400D01*
X454700Y176100D01*
Y175200D01*
G01X461844Y198275D02*
Y197253D01*
X460900Y196309D01*
Y185220D01*
X458778Y183098D01*
Y176970D01*
X458500Y176692D01*
Y175200D01*
G01X463444Y198275D02*
Y196590D01*
X462500Y195646D01*
Y194176D01*
X463752Y192924D01*
Y191454D01*
X462500Y190202D01*
Y184557D01*
X460378Y182435D01*
Y177014D01*
X460700Y176692D01*
Y175200D01*
G01X465734Y198291D02*
Y182077D01*
X464800Y181143D01*
Y176492D01*
X464500Y176192D01*
Y175200D01*
G01X467334Y198291D02*
Y192816D01*
X468639Y191511D01*
Y190041D01*
X467334Y188736D01*
Y181414D01*
X466400Y180480D01*
Y176492D01*
X466700Y176192D01*
Y175200D01*
G01X470500D02*
Y176848D01*
X470800Y177148D01*
Y192845D01*
X469666Y193979D01*
Y198741D01*
G01X471266D02*
Y194642D01*
X472400Y193508D01*
Y191732D01*
X473739Y190393D01*
Y188923D01*
X472400Y187584D01*
Y177100D01*
X472700Y176800D01*
Y175200D01*
G01X473615Y198291D02*
Y195492D01*
X476275Y192832D01*
Y175429D01*
X478400Y164389D01*
Y157700D01*
X478100Y157400D01*
Y156500D01*
G01X475215Y198291D02*
Y196155D01*
X477875Y193495D01*
Y175582D01*
X480000Y164542D01*
Y162960D01*
X481116Y161844D01*
Y160374D01*
X480000Y159258D01*
Y157900D01*
X480400Y157500D01*
Y156500D01*
G01X477549Y198291D02*
Y196431D01*
X481091Y192889D01*
Y179239D01*
X484404Y163650D01*
X485500Y158495D01*
Y157700D01*
X485100Y157300D01*
Y156500D01*
G01X479149Y198291D02*
Y197094D01*
X482691Y193552D01*
Y192082D01*
X484054Y190719D01*
Y189249D01*
X482691Y187886D01*
Y179408D01*
X487100Y158664D01*
Y157600D01*
X487400Y157300D01*
Y156500D01*
G01X481483Y198291D02*
Y197043D01*
X485930Y192596D01*
Y180018D01*
X488621Y167357D01*
X492400Y161539D01*
Y157800D01*
X492100Y157500D01*
Y156500D01*
G01X483083Y198291D02*
Y197706D01*
X487530Y193259D01*
Y191789D01*
X488845Y190474D01*
Y189004D01*
X487530Y187689D01*
Y180188D01*
X490125Y167980D01*
X494000Y162013D01*
Y157800D01*
X494400Y157400D01*
Y156500D01*
G01X488139Y197013D02*
X490168Y194985D01*
X493339Y190099D01*
X499701Y160167D01*
Y157601D01*
X499500Y157400D01*
Y156500D01*
G01X489270Y198145D02*
X491418Y195999D01*
X494843Y190722D01*
X501301Y160336D01*
Y157799D01*
X501800Y157300D01*
Y156500D01*
G01X531920Y242457D02*
X532520Y243057D01*
Y246655D01*
X530097Y249078D01*
X529052D01*
X527992Y248018D01*
X526522D01*
X525462Y249078D01*
X523992D01*
X520164Y252906D01*
X517860D01*
G01X534120Y242457D02*
Y247318D01*
X530760Y250678D01*
X524655D01*
X520827Y254506D01*
X517860D01*
G01X528401Y253967D02*
X528128Y254240D01*
X526362D01*
X523351Y257251D01*
X517296D01*
G01X528401Y256167D02*
X528074Y255840D01*
X527025D01*
X524014Y258851D01*
X522079D01*
X520979Y259951D01*
X519509D01*
X518409Y258851D01*
X517296D01*
G01X540100Y260900D02*
X538708D01*
X538408Y261200D01*
X517791D01*
X513968Y265023D01*
X513272D01*
G01X540100Y263100D02*
X538708D01*
X538408Y262800D01*
X523685D01*
X522585Y263900D01*
X521115D01*
X520015Y262800D01*
X518454D01*
X514631Y266623D01*
X513272D01*
G01X515055Y175822D02*
Y176755D01*
X515268Y176968D01*
Y178823D01*
X514290Y183429D01*
X518293Y192862D01*
X517732Y194251D01*
X518306Y195605D01*
X519696Y196166D01*
X520679Y198483D01*
X523716Y212765D01*
X521309Y224079D01*
X518580Y228283D01*
Y239466D01*
X517622Y240424D01*
G01X518754Y241555D02*
X520180Y240129D01*
Y228757D01*
X522813Y224702D01*
X525352Y212765D01*
X522213Y197999D01*
X515960Y183268D01*
X516868Y178992D01*
Y177251D01*
X517255Y176864D01*
Y175822D01*
G01X540100Y266900D02*
X538608D01*
X538462Y267046D01*
X537662D01*
X536684Y266068D01*
X520577D01*
X517762Y268883D01*
X517093D01*
G01X540100Y269100D02*
X539054D01*
X538600Y268646D01*
X536999D01*
X536021Y267668D01*
X526380D01*
X525280Y268768D01*
X523810D01*
X522710Y267668D01*
X521240D01*
X518425Y270483D01*
X517093D01*
G01X518523Y244751D02*
X522063Y241211D01*
Y230467D01*
X524511Y226703D01*
X527738Y211526D01*
X524952Y198420D01*
X526016Y193413D01*
X525200Y192156D01*
X525505Y190718D01*
X526762Y189902D01*
X526978Y188890D01*
X524932Y179269D01*
Y177682D01*
X524700Y177450D01*
Y175900D01*
G01X519655Y245882D02*
X523663Y241874D01*
Y230942D01*
X526015Y227327D01*
X529374Y211526D01*
X526588Y198420D01*
X528614Y188890D01*
X526532Y179100D01*
Y177950D01*
X526900Y177582D01*
Y175900D01*
G01X530893Y223067D02*
Y223473D01*
X531493Y224073D01*
Y227551D01*
X526687Y232357D01*
Y236288D01*
X525627Y237348D01*
Y238818D01*
X526687Y239878D01*
Y241348D01*
X519103Y248932D01*
X517978D01*
G01X533093Y223067D02*
Y228214D01*
X528287Y233020D01*
Y242011D01*
X519766Y250532D01*
X517978D01*
G01X540100Y273000D02*
X538608D01*
X538421Y273187D01*
X537528D01*
X536262Y271921D01*
X519119D01*
X518176Y272864D01*
X517430D01*
G01X540100Y275200D02*
X538608D01*
X538195Y274787D01*
X536865D01*
X535599Y273521D01*
X524442D01*
X523342Y274621D01*
X521872D01*
X520772Y273521D01*
X519782D01*
X518839Y274464D01*
X517430D01*
G01X540100Y279100D02*
X538608D01*
X538392Y279316D01*
X536851D01*
X534299Y276764D01*
X518737D01*
G01X540100Y281300D02*
X538783D01*
X538399Y280916D01*
X536188D01*
X533636Y278364D01*
X523877D01*
X522777Y279464D01*
X521307D01*
X520207Y278364D01*
X518737D01*
G01X540100Y285200D02*
X538608D01*
X538401Y285407D01*
X536112D01*
X532324Y281619D01*
X523534D01*
X522743Y280828D01*
X516965D01*
G01X540100Y287400D02*
X538608D01*
X538215Y287007D01*
X535449D01*
X531661Y283219D01*
X529000D01*
X527900Y284319D01*
X526430D01*
X525330Y283219D01*
X522871D01*
X522080Y282428D01*
X516965D01*
G01X539900Y291500D02*
X538408D01*
X538197Y291711D01*
X535631D01*
X531600Y287680D01*
X524680D01*
X521679Y284679D01*
X516975D01*
G01X539900Y293700D02*
X538408D01*
X538019Y293311D01*
X534968D01*
X530937Y289280D01*
X529576D01*
X528476Y290380D01*
X527006D01*
X525906Y289280D01*
X524017D01*
X521016Y286279D01*
X516975D01*
G01X509490Y301792D02*
X516941D01*
X528366Y313217D01*
X533525D01*
X533708Y313400D01*
X535200D01*
G01X509490Y300192D02*
X517604D01*
X518819Y301407D01*
X520375D01*
X521415Y302447D01*
Y304003D01*
X529029Y311617D01*
X533291D01*
X533708Y311200D01*
X535200D01*
G01X535000Y299800D02*
X533508D01*
X533315Y299607D01*
X528985D01*
X522115Y292737D01*
X510540D01*
G01X535000Y297600D02*
X533508D01*
X533101Y298007D01*
X529648D01*
X522778Y291137D01*
X515680D01*
X514580Y290037D01*
X513110D01*
X512010Y291137D01*
X510540D01*
G01X535100Y307300D02*
X533608D01*
X533421Y307113D01*
X529686D01*
X518165Y295592D01*
X514145D01*
X511892Y297845D01*
X509757D01*
G01X535100Y305100D02*
X533608D01*
X533195Y305513D01*
X530349D01*
X523160Y298324D01*
Y296768D01*
X522120Y295728D01*
X520564D01*
X518828Y293992D01*
X513482D01*
X511229Y296245D01*
X509757D01*
G01X535300Y319400D02*
X533808D01*
X533626Y319218D01*
X527032D01*
X517342Y309528D01*
Y306495D01*
X516170Y305323D01*
X510414D01*
G01X535300Y317200D02*
X533808D01*
X533390Y317618D01*
X527695D01*
X522577Y312500D01*
Y310944D01*
X521537Y309904D01*
X519981D01*
X518942Y308865D01*
Y305832D01*
X516833Y303723D01*
X510414D01*
G01X531920Y240257D02*
X532453Y239724D01*
Y234273D01*
X535999Y230727D01*
X539031Y216481D01*
X535056Y197757D01*
X538158Y183159D01*
X527225Y131727D01*
X536738Y86974D01*
X532665Y67805D01*
Y19435D01*
G03X535183Y16917I2518J0D01*
G01X536539D01*
G02X536871Y16779I0J-468D01*
G02X537008Y16448I-331J-331D01*
G01Y14961D01*
G01X534120Y240257D02*
X534053Y240190D01*
Y234937D01*
X537466Y231524D01*
X540667Y216481D01*
X539802Y212400D01*
X540618Y211143D01*
X540313Y209705D01*
X539056Y208888D01*
X538751Y207450D01*
X539567Y206193D01*
X539262Y204755D01*
X538005Y203938D01*
X537700Y202500D01*
X538516Y201243D01*
X538211Y199805D01*
X536954Y198988D01*
X536692Y197757D01*
X539794Y183159D01*
X528861Y131727D01*
X538374Y86974D01*
X534265Y67636D01*
Y19435D01*
G03X535183Y18517I918J0D01*
G01X536539D01*
G03X536871Y18655I0J468D01*
G03X537008Y18986I-331J331D01*
G01Y20473D01*
G01X530601Y253967D02*
X531467D01*
X531784Y254284D01*
X533280D01*
X534731Y252832D01*
X536940Y249432D01*
X544589Y213434D01*
X540608Y194711D01*
X543224Y182409D01*
X532370Y131339D01*
X543232Y80241D01*
X539752Y63869D01*
Y14710D01*
G03X542270Y12192I2518J0D01*
G01X543626D01*
G02X543958Y12054I0J-468D01*
G02X544095Y11723I-331J-331D01*
G01Y10237D01*
G01X530601Y256167D02*
X531533D01*
X531816Y255884D01*
X533944D01*
X535982Y253845D01*
X538444Y250055D01*
X546225Y213434D01*
X542244Y194711D01*
X542863Y191802D01*
X543481Y188893D01*
X544860Y182409D01*
X534006Y131339D01*
X544868Y80241D01*
X541352Y63700D01*
Y14710D01*
G03X542270Y13792I918J0D01*
G01X543626D01*
G03X543958Y13930I0J468D01*
G03X544095Y14261I-331J331D01*
G01Y15748D01*
G01X542300Y260900D02*
X543792D01*
X543994Y261102D01*
X548660D01*
X553924Y259887D01*
X557298Y257695D01*
X558250Y256229D01*
X560078Y253412D01*
X562105Y243870D01*
X558851Y228567D01*
X549772Y214590D01*
X545557Y194751D01*
X548611Y180385D01*
X537832Y129671D01*
X549494Y74795D01*
X546838Y62276D01*
Y19435D01*
G03X549356Y16917I2518J0D01*
G01X550712D01*
G02X551044Y16779I0J-468D01*
G02X551181Y16448I-331J-331D01*
G01Y14961D01*
G01X542300Y263100D02*
X543792D01*
X544190Y262702D01*
X548843D01*
X554559Y261383D01*
X558456Y258852D01*
X561582Y254035D01*
X563741Y243870D01*
X560355Y227944D01*
X551276Y213967D01*
X547193Y194751D01*
X550247Y180385D01*
X539468Y129671D01*
X551130Y74795D01*
X548438Y62108D01*
Y19435D01*
G03X549356Y18517I918J0D01*
G01X550712D01*
G03X551044Y18655I0J468D01*
G03X551181Y18986I-331J331D01*
G01Y20473D01*
G01X515748Y15748D02*
Y14261D01*
G02X515611Y13930I-468J0D01*
G02X515279Y13792I-332J330D01*
G01X513923D01*
G02X513005Y14710I0J918D01*
G01Y58728D01*
X513730Y62138D01*
X513972Y63275D01*
X513971D01*
X514115Y63953D01*
X516871Y76926D01*
X518129Y77743D01*
X518434Y79181D01*
X517617Y80438D01*
X517923Y81876D01*
X519180Y82693D01*
X519486Y84130D01*
X518669Y85388D01*
X518974Y86825D01*
X520232Y87642D01*
X520537Y89080D01*
X519721Y90337D01*
X520026Y91775D01*
X511833Y130331D01*
X518691Y162598D01*
X516900Y171025D01*
Y173267D01*
X517255Y173622D01*
G01X542300Y266900D02*
X543792D01*
X543982Y267090D01*
X548223D01*
X553851Y265894D01*
X560817Y261370D01*
X562794Y258326D01*
X564773Y255281D01*
X567275Y243521D01*
X563748Y226926D01*
X555990Y214981D01*
X551117Y192058D01*
X553727Y179782D01*
X542980Y129221D01*
X555738Y69199D01*
X553921Y60116D01*
X553925Y60112D01*
Y14710D01*
G03X556443Y12192I2518J0D01*
G01X557799D01*
G02X558131Y12054I0J-468D01*
G02X558268Y11723I-331J-331D01*
G01Y10237D01*
G01X542300Y269100D02*
X543792D01*
X544202Y268690D01*
X548392D01*
X554474Y267398D01*
X561974Y262527D01*
X566277Y255904D01*
X568911Y243521D01*
X565252Y226303D01*
X557494Y214358D01*
X552753Y192058D01*
X555363Y179782D01*
X544616Y129221D01*
X557372Y69209D01*
X555525Y59973D01*
Y14710D01*
G03X556443Y13792I918J0D01*
G01X557799D01*
G03X558131Y13930I0J468D01*
G03X558268Y14261I-331J331D01*
G01Y15748D01*
G01X522835Y14961D02*
Y16448D01*
G03X522698Y16779I-468J0D01*
G03X522366Y16917I-332J-330D01*
G01X521010D01*
G02X518492Y19435I0J2518D01*
G01Y63865D01*
X523863Y89130D01*
X515687Y127589D01*
X525050Y171639D01*
Y173350D01*
X524700Y173700D01*
G01X522835Y20473D02*
Y18986D01*
G02X522698Y18655I-468J0D01*
G02X522366Y18517I-332J330D01*
G01X521010D01*
G02X520092Y19435I0J918D01*
G01Y63696D01*
X525499Y89130D01*
X521128Y109691D01*
X521944Y110948D01*
X521639Y112386D01*
X520382Y113202D01*
X520076Y114640D01*
X520892Y115897D01*
X520587Y117335D01*
X519329Y118152D01*
X519024Y119589D01*
X519840Y120847D01*
X519534Y122285D01*
X518277Y123101D01*
X517323Y127589D01*
X526650Y171470D01*
Y173450D01*
X526900Y173700D01*
G01X530893Y220867D02*
X531493Y220267D01*
Y217358D01*
X532598Y212161D01*
Y209437D01*
X530116Y197767D01*
X533167Y183418D01*
X521557Y128804D01*
X524784Y113623D01*
X524783D01*
X530479Y86829D01*
X525579Y63776D01*
Y14710D01*
G03X528097Y12192I2518J0D01*
G01X529453D01*
G02X529785Y12054I0J-468D01*
G02X529922Y11723I-331J-331D01*
G01Y10237D01*
G01X533093Y220867D02*
Y217527D01*
X534198Y212330D01*
Y209268D01*
X531752Y197767D01*
X534803Y183418D01*
X523193Y128804D01*
X523499Y127366D01*
X524756Y126550D01*
X525061Y125112D01*
X524245Y123855D01*
X524551Y122417D01*
X525808Y121601D01*
X526113Y120163D01*
X525297Y118906D01*
X525603Y117468D01*
X526860Y116652D01*
X527165Y115214D01*
X526349Y113957D01*
X532115Y86829D01*
X527179Y63607D01*
Y14710D01*
G03X528097Y13792I918J0D01*
G01X529453D01*
G03X529785Y13930I0J468D01*
G03X529922Y14261I-331J331D01*
G01Y15748D01*
G01X542300Y273000D02*
X543792D01*
X544051Y273259D01*
X547494D01*
X555084Y271644D01*
X563725Y266028D01*
X566480Y261790D01*
X569236Y257549D01*
X572416Y242574D01*
X568789Y225509D01*
X562009Y215069D01*
X556621Y189718D01*
X558903Y178984D01*
X548205Y128645D01*
X561012Y68390D01*
Y19435D01*
G03X563530Y16917I2518J0D01*
G01X564886D01*
G02X565218Y16779I0J-468D01*
G02X565355Y16448I-331J-331D01*
G01Y14961D01*
G01X542300Y275200D02*
X543792D01*
X544133Y274859D01*
X547663D01*
X555707Y273148D01*
X564882Y267185D01*
X570740Y258172D01*
X574052Y242574D01*
X570293Y224886D01*
X563513Y214446D01*
X558257Y189718D01*
X560539Y178984D01*
X560469Y178651D01*
X560468D01*
X549841Y128645D01*
X562612Y68559D01*
Y19435D01*
G03X563530Y18517I918J0D01*
G01X564886D01*
G03X565218Y18655I0J468D01*
G03X565355Y18986I-331J331D01*
G01Y20473D01*
G01X542300Y279100D02*
X543792D01*
X543992Y279300D01*
X547374D01*
X557166Y277220D01*
X566072Y271436D01*
X570016Y265361D01*
X573960Y259285D01*
X577574Y242274D01*
X573651Y223815D01*
X568019Y215143D01*
X562138Y187468D01*
X564032Y178559D01*
X553421Y128636D01*
X568098Y59581D01*
Y14710D01*
G03X570616Y12192I2518J0D01*
G01X571972D01*
G02X572304Y12054I0J-468D01*
G02X572441Y11723I-331J-331D01*
G01Y10237D01*
G01X542300Y281300D02*
X543792D01*
X544192Y280900D01*
X547543D01*
X557789Y278724D01*
X567229Y272593D01*
X575464Y259908D01*
X579210Y242274D01*
X575155Y223192D01*
X569523Y214520D01*
X563774Y187468D01*
X565668Y178559D01*
X555057Y128636D01*
X569698Y59750D01*
Y14710D01*
G03X570616Y13792I918J0D01*
G01X571972D01*
G03X572304Y13930I0J468D01*
G03X572441Y14261I-331J331D01*
G01Y15748D01*
G01X542300Y285200D02*
X543792D01*
X544036Y285444D01*
X549406D01*
X555403Y284169D01*
X570159Y274585D01*
X574381Y268084D01*
X578604Y261582D01*
X582781Y241940D01*
X578596Y222249D01*
X574084Y215300D01*
Y215301D01*
X567647Y184981D01*
X569160Y177865D01*
X558653Y128433D01*
X575185Y50650D01*
Y19435D01*
G03X577703Y16917I2518J0D01*
G01X579059D01*
G02X579391Y16779I0J-468D01*
G02X579528Y16448I-331J-331D01*
G01Y14961D01*
G01X542300Y287400D02*
X543792D01*
X544148Y287044D01*
X549575D01*
X556026Y285673D01*
X571316Y275742D01*
X580108Y262205D01*
X584417Y241940D01*
X580100Y221626D01*
X575588Y214678D01*
X569283Y184981D01*
X570796Y177865D01*
X560289Y128433D01*
X576785Y50819D01*
Y19435D01*
G03X577703Y18517I918J0D01*
G01X579059D01*
G03X579391Y18655I0J468D01*
G03X579528Y18986I-331J331D01*
G01Y20473D01*
G01X542100Y291500D02*
X543592D01*
X543833Y291741D01*
X545780D01*
X556037Y289561D01*
X573913Y277949D01*
X578724Y270539D01*
X583536Y263128D01*
X587865Y241472D01*
X583400Y220465D01*
X580325Y215730D01*
X573171Y182224D01*
X574449Y176220D01*
X563924Y126708D01*
X577411Y63265D01*
X581662Y56719D01*
X582271Y53853D01*
Y14710D01*
G03X584789Y12192I2518J0D01*
G01X586145D01*
G02X586477Y12054I0J-468D01*
G02X586614Y11723I-331J-331D01*
G01Y10237D01*
G01X542100Y293700D02*
X543592D01*
X543951Y293341D01*
X545949D01*
X556660Y291065D01*
X575071Y279106D01*
X585045Y263742D01*
X589499Y241462D01*
X584904Y219842D01*
X581829Y215106D01*
X574808Y182223D01*
X576085Y176220D01*
X565560Y126708D01*
X578915Y63888D01*
X583166Y57342D01*
X583871Y54021D01*
Y14710D01*
G03X584789Y13792I918J0D01*
G01X586145D01*
G03X586477Y13930I0J468D01*
G03X586614Y14261I-331J331D01*
G01Y15748D01*
G54D27*
X166138Y432870D03*
X542495Y471383D03*
X604226Y252452D03*
X639200Y252000D03*
G54D81*
X780495Y517441D03*
G54D72*
X658116Y36660D03*
Y34100D03*
Y31540D03*
X651616D03*
Y36660D03*
G54D54*
X367340Y250340D03*
Y253940D03*
X367368Y278487D03*
Y282087D03*
X367177Y306562D03*
Y310162D03*
X422323Y284048D03*
Y287648D03*
X418323Y284048D03*
Y287648D03*
X467534Y252200D03*
Y255800D03*
X467547Y259450D03*
Y263050D03*
X467537Y268396D03*
Y271996D03*
X775407Y123893D03*
Y127493D03*
G54D63*
G01X426300Y249250D02*
X427916D01*
X429134Y248032D01*
X374432Y316002D03*
X425197Y236220D03*
X425196Y228347D03*
X433070Y236221D03*
X440944D03*
X448818D03*
X433070Y228347D03*
X440944D03*
X448818D03*
X405512Y212599D03*
X393701Y208662D03*
X401575D03*
X409449D03*
X417323D03*
X425197D03*
X433071D03*
X440945D03*
X448819D03*
X413386Y212599D03*
X421260D03*
X429134D03*
X437008D03*
X444882D03*
X421258Y232283D03*
X448818Y232284D03*
X440944D03*
X433070D03*
X433071Y224410D03*
X440945D03*
X448819D03*
X397638Y232284D03*
X389764Y204725D03*
Y220473D03*
Y208662D03*
Y228347D03*
X409449Y236221D03*
X393701Y228347D03*
Y216536D03*
Y212599D03*
X397638D03*
X401575D03*
X393701Y220473D03*
X397638Y200788D03*
X405512D03*
X413386D03*
X421260D03*
X429134D03*
X437008D03*
X444882D03*
X409449Y212599D03*
Y224410D03*
X417323Y212599D03*
X425197D03*
X433071D03*
X440945D03*
X448819D03*
X425197Y224410D03*
X417323D03*
X413386D03*
X409449Y232284D03*
X397638Y236221D03*
Y228347D03*
Y224410D03*
X389000Y236100D03*
X401575Y236221D03*
X405512D03*
X417322D03*
X409449Y220473D03*
Y216536D03*
X413386Y220473D03*
Y216536D03*
X417323Y220473D03*
Y216536D03*
X421260Y220473D03*
Y216536D03*
X425197Y220473D03*
Y216536D03*
X429134Y220473D03*
Y216536D03*
X433071Y220473D03*
Y216536D03*
X437008Y220473D03*
Y216536D03*
X440945Y220473D03*
Y216536D03*
X444882Y220473D03*
Y216536D03*
X448819Y220473D03*
Y216536D03*
X409449Y204725D03*
Y200788D03*
X413386Y208662D03*
Y204725D03*
X417323D03*
Y200788D03*
X421260Y208662D03*
Y204725D03*
X425197D03*
Y200788D03*
X429134Y208662D03*
Y204725D03*
X433071D03*
Y200788D03*
X437008Y208662D03*
Y204725D03*
X440945D03*
Y200788D03*
X444882Y208662D03*
Y204725D03*
X448819D03*
Y200788D03*
X389764Y216536D03*
Y212599D03*
X397638Y220473D03*
Y216536D03*
X401575Y220473D03*
Y216536D03*
X405512Y220473D03*
Y216536D03*
X393701Y204725D03*
Y200788D03*
X397638Y208662D03*
Y204725D03*
X401575D03*
Y200788D03*
X405512Y208662D03*
Y204725D03*
X401575Y232284D03*
X401727Y228641D03*
X405512Y232284D03*
X413386D03*
X405512Y228347D03*
X409449Y259843D03*
X425197Y291339D03*
X433071Y295276D03*
Y299213D03*
Y291339D03*
X448819Y287403D03*
X448818Y291339D03*
Y295276D03*
X437008Y299213D03*
Y291339D03*
X448818Y299214D03*
X425196Y283466D03*
X433070Y279528D03*
X433071Y275591D03*
X433070Y255905D03*
X437057Y279414D03*
X397638Y240158D03*
Y295276D03*
X405512D03*
X397638Y271654D03*
X409449Y267717D03*
X397638Y287402D03*
X405512D03*
X397638Y279528D03*
X409449Y275591D03*
X397638Y259843D03*
X405512D03*
Y255906D03*
X389764Y251969D03*
X393701D03*
X397638D03*
X409449Y244095D03*
Y255906D03*
X417323Y299213D03*
X421260Y291339D03*
X425197Y259843D03*
X417323Y267717D03*
X429134Y271654D03*
X417323Y275591D03*
X429134Y248032D03*
X425197Y255906D03*
X417323D03*
X413386Y259843D03*
X429134Y279528D03*
X421260D03*
X433071Y240158D03*
Y248032D03*
X448819Y240158D03*
X440945D03*
X444882Y279529D03*
X448819Y248032D03*
X440945D03*
X448818Y259843D03*
Y267718D03*
X440944D03*
X433071Y263781D03*
X440944Y259843D03*
X429134Y295277D03*
Y299214D03*
X437007Y287402D03*
X429134Y291340D03*
X437008Y275591D03*
X444882D03*
X437007Y267718D03*
X448818Y255906D03*
Y263780D03*
Y271655D03*
X440944Y263780D03*
Y271655D03*
X437007Y259843D03*
Y255905D03*
X440944Y255906D03*
X421260Y259843D03*
X429134Y263781D03*
Y255906D03*
X433071Y283465D03*
X425197Y287402D03*
X444882D03*
X440945Y283465D03*
X448819D03*
X444882Y299213D03*
X425196Y240158D03*
X409449D03*
Y248032D03*
X397638Y244095D03*
X421260Y255906D03*
X425197Y299213D03*
X429134Y287403D03*
X417323Y259843D03*
X413386Y255906D03*
X440945Y295276D03*
Y299213D03*
Y291339D03*
Y287402D03*
X437008Y295276D03*
X429134Y251969D03*
X417323D03*
X413386Y248032D03*
X405512D03*
X421260Y251969D03*
X405512Y244095D03*
X401575D03*
X413386D03*
X417323Y248032D03*
X401575Y240158D03*
X405512D03*
X433070Y287402D03*
X413387Y240158D03*
X421260Y248032D03*
X417323Y244095D03*
X413386Y251969D03*
X401575Y248032D03*
X421260Y295277D03*
X448819Y244095D03*
X440945D03*
X433071D03*
X421259Y240158D03*
X421260Y244095D03*
X417323Y240157D03*
X421260Y299214D03*
X425197Y295276D03*
X413386Y311025D03*
X425197Y318898D03*
Y303150D03*
X429134Y314961D03*
Y311024D03*
X448819Y307088D03*
X448818Y311024D03*
Y303151D03*
X444882Y314961D03*
Y318898D03*
X433071Y314961D03*
X431102Y331263D03*
X397638Y326772D03*
X409449D03*
X397638Y318898D03*
X409449D03*
Y314961D03*
X397638Y311024D03*
X409449D03*
X417323Y326772D03*
Y318898D03*
X425197Y311024D03*
X433071D03*
X397638Y303150D03*
X405512D03*
X413386Y307087D03*
X440945Y318898D03*
X448819D03*
X417323Y307087D03*
Y303150D03*
X429134Y303151D03*
X425197Y314961D03*
X413386Y326772D03*
X425197Y307087D03*
X417323Y314961D03*
X433071Y307087D03*
X448819Y314961D03*
X440945D03*
X417323Y311024D03*
X429134Y318898D03*
X442800Y330300D03*
X446200Y327400D03*
X440945Y303150D03*
Y311024D03*
Y307087D03*
X444881Y322835D03*
X442913Y327204D03*
X440944Y322835D03*
X438976Y327204D03*
X437008Y318898D03*
Y314961D03*
Y311024D03*
Y303150D03*
Y307087D03*
X433071Y318898D03*
X421260Y326772D03*
X421259Y322835D03*
X421260Y318898D03*
Y314961D03*
X417322Y322835D03*
X413386Y314962D03*
X421260Y307088D03*
X433071Y303150D03*
X421260Y303151D03*
X456693Y236221D03*
X464567D03*
X472441D03*
X460630Y208662D03*
X468504D03*
X484252D03*
X476378D03*
X496063D03*
X456693Y212599D03*
X464567D03*
X503937Y216536D03*
X472441Y212599D03*
X480315D03*
X488189D03*
X507874D03*
Y236221D03*
X503937Y232284D03*
X507874Y228347D03*
X503937Y224410D03*
X507874Y220473D03*
X472441Y228347D03*
X464567D03*
X456693D03*
X480315D03*
X484252Y236221D03*
X488189Y232284D03*
X456693D03*
X464567D03*
X472441D03*
X480315D03*
X456693Y200788D03*
X464567D03*
X492126Y208662D03*
Y204725D03*
X500000D03*
X472441Y200788D03*
X480315D03*
X488189D03*
X492126D03*
X460630Y212599D03*
X468504D03*
X492126Y216536D03*
X476378Y212599D03*
X484252D03*
X492126D03*
X503937D03*
X507874Y208662D03*
X503937Y204725D03*
X507874D03*
X503937Y236221D03*
Y228347D03*
X492126Y220473D03*
X503937D03*
X511811Y208662D03*
X507874Y200788D03*
X511811D03*
X472441Y224410D03*
X464567D03*
X456693D03*
X480315D03*
X492126D03*
X488189D03*
X492126Y232284D03*
Y236221D03*
X500000Y200788D03*
X503937D03*
X456693Y220473D03*
Y216536D03*
X460630Y220473D03*
Y216536D03*
X464567Y220473D03*
Y216536D03*
X468504Y220473D03*
Y216536D03*
X472441Y220473D03*
Y216536D03*
X476378Y220473D03*
Y216536D03*
X480315Y220473D03*
Y216536D03*
X484252Y220473D03*
Y216536D03*
X488189Y220473D03*
Y216536D03*
X500000Y208662D03*
X503937D03*
X496063Y212599D03*
X500000D03*
X496063Y216536D03*
X500000D03*
X496063Y220473D03*
X500000D03*
X496063Y224410D03*
X500000D03*
X496063Y228347D03*
X500000D03*
X496063Y232284D03*
X500000D03*
X496063Y236221D03*
X500000D03*
X456693Y208662D03*
Y204725D03*
X460630D03*
Y200788D03*
X464567Y208662D03*
Y204725D03*
X468504D03*
Y200788D03*
X472441Y208662D03*
Y204725D03*
X476378D03*
Y200788D03*
X480315Y208662D03*
Y204725D03*
X484252D03*
Y200788D03*
X488189Y208662D03*
Y204725D03*
X468504Y299214D03*
X472442Y287402D03*
X480315Y295276D03*
X484252Y295277D03*
X476378Y291339D03*
X452755Y287402D03*
Y291340D03*
Y295277D03*
X503937Y255906D03*
X507874Y251969D03*
X503937Y248032D03*
X507874Y244095D03*
X503937Y240158D03*
X507874Y271654D03*
X503937Y267717D03*
X507874Y259843D03*
Y287402D03*
X503937Y283465D03*
X507874Y279528D03*
X503937Y275591D03*
Y299213D03*
X507874Y295276D03*
X503937Y291339D03*
X492126Y287402D03*
X484252Y271654D03*
Y279528D03*
X488189Y267717D03*
Y275591D03*
X492126Y271654D03*
Y279528D03*
X488189Y283465D03*
X484252Y259843D03*
Y251969D03*
Y244095D03*
X492126Y259843D03*
Y251969D03*
Y244095D03*
X464567Y299214D03*
X456693Y279528D03*
Y267718D03*
X464567D03*
X472441Y295276D03*
X503937Y251969D03*
Y244095D03*
Y271654D03*
Y259843D03*
Y287402D03*
Y279528D03*
Y295276D03*
X488189Y287402D03*
X492126Y291339D03*
X488189D03*
X472441Y240158D03*
X456693Y259843D03*
X464567Y240158D03*
X456693D03*
X480315Y267717D03*
Y271654D03*
Y275591D03*
Y279528D03*
Y283465D03*
X492126Y267717D03*
X488189Y271654D03*
X492126Y275591D03*
X488189Y279528D03*
X492126Y283465D03*
X480315Y259843D03*
Y240158D03*
Y244095D03*
Y248032D03*
Y251969D03*
Y255906D03*
X488189Y259843D03*
X492126Y240158D03*
X488189D03*
X492126Y248032D03*
X488189D03*
Y255906D03*
X452757Y279529D03*
X464567D03*
X472441Y275591D03*
Y267717D03*
Y283465D03*
Y259843D03*
Y251969D03*
X456693Y248032D03*
X464567D03*
Y259843D03*
X472441Y291339D03*
X464568Y287402D03*
X460630Y275592D03*
X464568D03*
X452756D03*
X456693Y255906D03*
X464567D03*
Y263780D03*
X456693D03*
X464567Y271655D03*
X456693D03*
X476379Y287402D03*
X472441Y299213D03*
X480315D03*
X488189D03*
X456693Y287402D03*
X460630Y283465D03*
X468504D03*
X468505Y287402D03*
X460631Y295277D03*
X456693Y299213D03*
X460630D03*
X480316Y287403D03*
X484252Y291340D03*
Y287402D03*
X488189Y295276D03*
X456694D03*
X496063Y255906D03*
X500000D03*
X496063Y259843D03*
X500000D03*
X496063Y267717D03*
X500000D03*
X496063Y240158D03*
X500000D03*
X496063Y244095D03*
X500000D03*
X496063Y271654D03*
X500000D03*
X496063Y248032D03*
X500000D03*
X496063Y251969D03*
X500000D03*
X496063Y275591D03*
X500000D03*
X496063Y279528D03*
X500000D03*
X496063Y283465D03*
X500000D03*
X496063Y287402D03*
X500000D03*
X507874Y255906D03*
X511811D03*
Y259843D03*
X507874Y267717D03*
X511811D03*
X507874Y240158D03*
X511811D03*
Y244095D03*
Y271654D03*
X507874Y248032D03*
X511811D03*
Y251969D03*
X507874Y275591D03*
X511811D03*
Y279528D03*
X507874Y283465D03*
X511811D03*
Y287402D03*
X480315Y291339D03*
X496063Y299213D03*
X500000D03*
X496063Y291339D03*
X500000D03*
X496063Y295276D03*
X500000D03*
X476378Y267717D03*
Y275591D03*
Y259843D03*
Y251969D03*
X472441Y244095D03*
X464567D03*
X456693D03*
Y291339D03*
X460630D03*
X500001Y314961D03*
X503937Y318898D03*
X488189Y307087D03*
X492126Y311024D03*
X460630Y307087D03*
X456693D03*
X460630Y311024D03*
X462599Y327204D03*
X456693Y311024D03*
Y314961D03*
X452755Y307087D03*
Y303150D03*
X456693Y318898D03*
X507874Y303150D03*
X472441D03*
X460630Y318898D03*
X468504D03*
X456693Y303150D03*
X476378Y318898D03*
X484252D03*
X492126D03*
X500000D03*
X496063Y307087D03*
X480315Y303150D03*
X492126D03*
X507874Y318898D03*
Y307087D03*
X511811D03*
X503937Y303150D03*
X484252D03*
X496063Y318898D03*
X488189Y311024D03*
X484252Y307087D03*
Y314961D03*
X476378D03*
X468504D03*
X507874D03*
X492126D03*
X500000Y311025D03*
X460630Y314961D03*
X496063D03*
X476378Y311024D03*
X472441Y307087D03*
X488189Y303150D03*
X500000Y307088D03*
X503937Y311024D03*
X468504Y303151D03*
X460630Y303150D03*
X464567Y303151D03*
X503937Y307087D03*
X507874Y311024D03*
X464567Y307088D03*
X468505D03*
X472441Y314961D03*
X492126Y307087D03*
X496063Y311024D03*
X464567Y311025D03*
Y318898D03*
X472441D03*
X496063Y303150D03*
X500000D03*
X470473Y327204D03*
X468504Y311024D03*
X488189Y322835D03*
X517000Y226370D03*
Y218500D03*
Y234252D03*
X517500Y297218D03*
X518647Y288943D03*
X515748Y240158D03*
Y267717D03*
Y255906D03*
Y248032D03*
Y283465D03*
Y275591D03*
Y259843D03*
Y244095D03*
Y271654D03*
Y251969D03*
Y279528D03*
Y287402D03*
Y318898D03*
Y307087D03*
X516500Y313000D03*
X666928Y144880D03*
X682675Y132281D03*
X688974D03*
X660630Y122834D03*
X660629Y119685D03*
X663779Y122834D03*
Y119685D03*
X670079Y122835D03*
X670078Y119685D03*
X673229Y122835D03*
X673228Y119685D03*
X679528Y122835D03*
X679527Y119685D03*
X682678Y122835D03*
X682677Y119685D03*
X688977Y122835D03*
X688976Y119685D03*
X692126Y122835D03*
Y119686D03*
G54D18*
X34567Y205090D03*
X128611Y331774D03*
X121506Y349295D03*
X129133Y339988D03*
X114258Y351996D03*
X186054Y105503D03*
X170652Y119800D03*
X177400Y149700D03*
X140561Y420016D03*
X140820Y436738D03*
X140712Y444036D03*
X204818Y107083D03*
X238000Y149500D03*
X248746Y140710D03*
X246764Y199671D03*
X237682Y343985D03*
X259132Y405962D03*
X226076Y407980D03*
X226376Y419280D03*
X250400Y407800D03*
X237276Y408080D03*
X237576Y419380D03*
X248698Y372535D03*
X276700Y66700D03*
X307243Y156439D03*
X270486Y130871D03*
X320000Y180000D03*
X316500Y228500D03*
X316263Y211751D03*
X275519Y213859D03*
X323700Y284500D03*
X309300Y283300D03*
X306292Y252825D03*
X302262Y262642D03*
X296000Y287000D03*
X276070Y401100D03*
X321467Y383273D03*
X298152Y389992D03*
X269742Y380801D03*
X266050Y385047D03*
X344484Y265072D03*
X343314Y272604D03*
X383677Y252037D03*
X379700Y279906D03*
X385803Y260151D03*
X332000Y266336D03*
X337500Y266050D03*
X371160Y314500D03*
X386159Y327300D03*
X335133Y412340D03*
X407484Y262952D03*
X437233Y263915D03*
X391839Y263634D03*
X389709Y245772D03*
X413115Y323215D03*
X425737Y325715D03*
X427165Y316929D03*
X435039D03*
X442913Y320866D03*
X431203Y326380D03*
X401700Y340950D03*
X392453Y331635D03*
X496828Y199110D03*
X505776Y198689D03*
X484392Y298681D03*
X477955Y301006D03*
X490158Y309055D03*
X500300Y328154D03*
X479600Y310300D03*
X501227Y354336D03*
X460484Y350953D03*
X491445Y342700D03*
X474210Y316992D03*
X462663Y323248D03*
X475834Y331163D03*
X481856Y352656D03*
X468257Y323578D03*
X498032Y312992D03*
X473265Y322929D03*
X454724Y301181D03*
X495050Y373662D03*
X506684Y455873D03*
X529512Y352016D03*
X572204Y407700D03*
X570669Y465918D03*
X532050Y476200D03*
X550100Y479850D03*
X569400Y483400D03*
X569402Y472058D03*
X561657Y461261D03*
X540140Y489830D03*
X633803Y27749D03*
X629500Y118500D03*
X599000Y236500D03*
X630500Y212900D03*
X631600Y271000D03*
X603000Y279000D03*
X611606Y322456D03*
X623969Y319984D03*
X594200Y395200D03*
X604832Y395220D03*
X605148Y440842D03*
X587250Y463750D03*
X577390Y453170D03*
X621308Y468700D03*
X633850Y452930D03*
X609768Y487900D03*
X652587Y21500D03*
X639426Y49015D03*
X640144Y40969D03*
X659850Y42534D03*
X639900Y27100D03*
X646000Y62259D03*
X661644Y164498D03*
X636630Y154650D03*
X645729Y161603D03*
X657700Y139700D03*
X657570Y146235D03*
X663800Y148100D03*
X680425Y205984D03*
X656427Y226217D03*
X638361Y212930D03*
X673100Y238300D03*
X652000Y220500D03*
X668153Y210095D03*
X650904Y226864D03*
X684696Y236469D03*
X695253Y214735D03*
X689783Y215075D03*
X686982Y262854D03*
X678720Y288330D03*
X686912Y268500D03*
X653707Y342389D03*
X667400Y384700D03*
X662029Y384727D03*
X657031Y384900D03*
X680700Y373763D03*
X684017Y389383D03*
X650530Y379699D03*
X668800Y478000D03*
X668300Y464300D03*
X701900Y106000D03*
X712399Y160987D03*
X732579Y152616D03*
X715490Y131490D03*
X749533Y160800D03*
X749500Y145050D03*
X750000Y141000D03*
X748000Y167000D03*
X703290Y205505D03*
X716096Y272396D03*
X700600Y256539D03*
X711401Y477794D03*
X804300Y111300D03*
X785050Y79670D03*
X771371Y98500D03*
X766694Y86024D03*
X767200Y113600D03*
X800000Y145240D03*
X793378Y145309D03*
X785756Y145353D03*
X805200Y170300D03*
X804600Y130300D03*
X773100Y132000D03*
X765900Y119700D03*
X790050Y178350D03*
X782850D03*
X795450Y178550D03*
X800500Y232750D03*
X775486Y287316D03*
G54D36*
X262600Y411100D03*
X301000Y159200D03*
X300500Y199200D03*
Y241700D03*
X362868Y263441D03*
X362689Y291541D03*
X631781Y128708D03*
X639120Y452330D03*
X776500Y108700D03*
X790000Y92700D03*
X776500D03*
G54D45*
X283000Y289700D03*
X316786Y389942D03*
X358169Y268768D03*
X358222Y296041D03*
X413400Y344000D03*
X417400D03*
X449400Y334200D03*
X427500Y344000D03*
X432900Y344300D03*
X445400Y334200D03*
X447300Y344300D03*
X391900Y344100D03*
X450200Y325600D03*
X510000Y355000D03*
X506000D03*
X505379Y345211D03*
X501281D03*
X509517Y345246D03*
X455900Y344200D03*
X478618Y342842D03*
X502200Y364009D03*
X547908Y335132D03*
X541747Y335165D03*
X529947Y335200D03*
X525522Y345246D03*
X529622D03*
X558000Y351700D03*
X554000D03*
X533947Y335200D03*
X540200Y354800D03*
X536200D03*
X545200D03*
X549200D03*
X633000Y65700D03*
X636000Y206700D03*
X632000D03*
X624000D03*
X628000D03*
X618026Y264952D03*
X611526D03*
X659850Y50200D03*
X641003Y65709D03*
X640000Y206700D03*
X648000D03*
X652000D03*
X644000D03*
X656000D03*
X660000D03*
X645500Y264600D03*
X652000D03*
X672131Y386583D03*
X717500Y138650D03*
X713500D03*
X710800Y218000D03*
X719700D03*
X785350Y87700D03*
X794500Y140800D03*
X782500D03*
X798500D03*
X796500Y232700D03*
G54D91*
G01X660630Y122834D02*
X662205Y120270D01*
X662204Y119757D01*
Y119033D01*
X662203Y119032D01*
X662204Y119031D01*
X662200Y119027D01*
Y118526D01*
X663225Y117501D01*
Y114853D01*
X661660Y113287D01*
X661040Y112665D01*
X661041Y112315D01*
X660975Y112249D01*
G01X660108Y113114D02*
X660174Y113180D01*
X660528D01*
X661146Y113800D01*
X662500Y115154D01*
Y117200D01*
X661475Y118225D01*
Y118838D01*
X661249Y119064D01*
X661229Y119083D01*
X661121Y119190D01*
X660629Y119685D01*
G01X663779Y122834D02*
X665300Y120358D01*
Y112030D01*
X664085Y110814D01*
X663669Y110399D01*
X662983Y109713D01*
Y109448D01*
X662917Y109382D01*
G01X663779Y119685D02*
X664575Y118889D01*
Y112331D01*
X663572Y111328D01*
X663156Y110913D01*
X662722Y110478D01*
X662608Y110364D01*
X662166D01*
X662100Y110298D01*
G01X670079Y122835D02*
X671653Y120243D01*
Y116653D01*
X670491Y115491D01*
Y114254D01*
X670652Y114093D01*
Y114000D01*
G01X670078Y119685D02*
X670928Y118835D01*
Y116954D01*
X669766Y115792D01*
Y114432D01*
X669427Y114093D01*
Y114000D01*
G01X673229Y122835D02*
X674766Y120346D01*
Y118817D01*
X674702Y118753D01*
Y114562D01*
X674952Y114312D01*
Y114219D01*
G01X673228Y119685D02*
X673977Y118936D01*
Y114562D01*
X673727Y114312D01*
Y114219D01*
G01X679528Y122835D02*
X681102Y120165D01*
Y119033D01*
X681105Y119030D01*
X681070Y118995D01*
Y117343D01*
X681320Y117093D01*
Y117000D01*
G01X679527Y119685D02*
X680345Y118867D01*
Y117343D01*
X680095Y117093D01*
Y117000D01*
G01X682678Y122835D02*
X684291Y120099D01*
Y118884D01*
X683848Y118441D01*
Y116343D01*
X684098Y116093D01*
Y116000D01*
G01X682677Y119685D02*
X683123Y119239D01*
Y116343D01*
X682873Y116093D01*
Y116000D01*
G01X690626Y117632D02*
Y117679D01*
X690389Y117916D01*
Y118863D01*
X690555Y119029D01*
X690551Y119033D01*
Y120165D01*
X688977Y122835D01*
G01X688976Y119685D02*
X689664Y118997D01*
Y117988D01*
X689401Y117725D01*
Y117632D01*
G01X692126Y122835D02*
X693754Y120073D01*
Y119079D01*
X693547Y118872D01*
Y117384D01*
X695767Y115164D01*
Y112027D01*
X695967Y111827D01*
Y111734D01*
G01X692126Y119686D02*
X692822Y118990D01*
Y117083D01*
X695042Y114863D01*
Y112127D01*
X694742Y111827D01*
Y111734D01*
G54D82*
G01X316015Y297650D02*
Y290135D01*
G01D02*
X316050Y290100D01*
G01X343575Y297650D02*
Y293675D01*
X342150Y292250D01*
Y289600D01*
G01X451500Y209400D02*
X449557D01*
X448819Y208662D01*
G01X451500Y211600D02*
X449818D01*
X448819Y212599D01*
G01X395500Y233100D02*
X396822D01*
X397638Y232284D01*
G01X393701Y228347D02*
X394700Y229346D01*
Y230300D01*
G01X407500Y237100D02*
X408570D01*
X409449Y236221D01*
G01X411398Y231600D02*
X410133D01*
X409449Y232284D01*
G01X395500Y235300D02*
X396717D01*
X397638Y236221D01*
G01X396900Y230300D02*
Y229085D01*
X397638Y228347D01*
G01X395500Y241000D02*
X396796D01*
X397638Y240158D01*
G01X447768Y297155D02*
Y298164D01*
X448818Y299214D01*
G01X445568Y297155D02*
Y298527D01*
X444882Y299213D01*
G01X427635Y241981D02*
X426173D01*
X425196Y241004D01*
Y240158D01*
G01X407500Y239300D02*
X408591D01*
X409449Y240158D01*
G01X409000Y250900D02*
Y248481D01*
X409449Y248032D01*
G01X395500Y243200D02*
X396743D01*
X397638Y244095D01*
G01X451100Y317900D02*
X449817D01*
X448819Y318898D01*
G01X451100Y315700D02*
X449558D01*
X448819Y314961D01*
G01X496059Y205807D02*
Y208658D01*
X496063Y208662D01*
G01X496059Y203607D02*
X493244D01*
X492126Y204725D01*
G01X502722Y218500D02*
Y219258D01*
X503937Y220473D01*
G01X502722Y222450D02*
Y221688D01*
X503937Y220473D01*
G01X502722Y226350D02*
Y227132D01*
X503937Y228347D01*
G01X502722Y230291D02*
Y229562D01*
X503937Y228347D01*
G01X502722Y234219D02*
Y235006D01*
X503937Y236221D01*
G01X502722Y214576D02*
Y213814D01*
X503937Y212599D01*
G01X507100Y262500D02*
Y260617D01*
X507874Y259843D01*
G01X508186Y289438D02*
Y287714D01*
X507874Y287402D01*
G01X504900Y262500D02*
Y260806D01*
X503937Y259843D01*
G01X462600Y300400D02*
X463381D01*
X464567Y299214D01*
G01X488189Y287402D02*
X488141Y287450D01*
X486250D01*
G01X488189Y291339D02*
X489200Y290328D01*
Y289300D01*
G01X492126Y291339D02*
X492587Y291800D01*
X494100D01*
G01X505986Y289438D02*
X504937D01*
X503937Y288438D01*
Y287402D01*
G01X474520Y285600D02*
X476322Y287402D01*
X476379D01*
G01X478400Y285600D02*
X476598Y287402D01*
X476379D01*
G01X474500Y299900D02*
X473128D01*
X472441Y299213D01*
G01X462600Y298200D02*
Y297246D01*
X460631Y295277D01*
G01X486308Y318242D02*
X484908D01*
X484252Y318898D01*
G01X497000Y309020D02*
Y308024D01*
X496063Y307087D01*
G01X474500Y302100D02*
X473491D01*
X472441Y303150D01*
G01X458667Y318105D02*
X459837D01*
X460630Y318898D01*
G01X486308Y316042D02*
X485333D01*
X484252Y314961D01*
G01X512700Y317400D02*
X511400D01*
X508961Y314961D01*
X507874D01*
G01X499200Y309020D02*
X499980Y309800D01*
X500000D01*
Y311025D01*
G01X458667Y315905D02*
X459686D01*
X460630Y314961D01*
G01X512400Y310000D02*
Y307676D01*
X511811Y307087D01*
G01X512700Y319600D02*
X515046D01*
X515748Y318898D01*
G01X514600Y310000D02*
Y311100D01*
X516500Y313000D01*
G01X651483Y108996D02*
Y111296D01*
G01X677505Y112037D02*
Y109468D01*
X678189Y108784D01*
G01X651483Y111296D02*
X655083D01*
X657172Y113385D01*
X657480D01*
G01X672297Y129076D02*
Y126917D01*
X673229Y125985D01*
G01X698426Y122835D02*
X697700Y122109D01*
Y119500D01*
G01X660650Y128650D02*
Y126004D01*
X657480Y122834D01*
G01X677505Y114237D02*
Y115408D01*
X676377Y116536D01*
G01X656875Y171352D02*
X655604D01*
X654330Y170078D01*
G01X667843Y170060D02*
X670060D01*
X670078Y170078D01*
G01X656875Y173552D02*
X654654D01*
X654330Y173228D01*
G01X670097Y129076D02*
X666987D01*
X666929Y129134D01*
G01Y119685D02*
Y122835D01*
X670079Y125985D01*
G01X656944Y177304D02*
X656017Y176377D01*
X654330D01*
G01Y182676D02*
X656748D01*
X657045Y182973D01*
G01X663507Y189280D02*
Y191853D01*
X663779Y192125D01*
G01X657737Y194808D02*
Y192382D01*
X657480Y192125D01*
G01X671452Y200715D02*
Y196025D01*
X671142Y195715D01*
G01X657045Y185173D02*
X654983D01*
X654330Y185826D01*
G01X656944Y179504D02*
X654352D01*
X654330Y179526D01*
G01X686992Y189743D02*
Y190959D01*
X685826Y192125D01*
G01X684682Y195495D02*
Y196518D01*
X682834Y198366D01*
Y201545D01*
G01X685826Y192125D02*
Y193624D01*
X684682Y194768D01*
Y195495D01*
G01X692141Y189723D02*
Y192109D01*
X692125Y192125D01*
G01X699245Y111675D02*
Y109133D01*
X699563Y108815D01*
G01X699245Y113875D02*
Y115715D01*
X698425Y116535D01*
G01X716400Y125000D02*
Y123756D01*
X717322Y122834D01*
G01X710900Y125000D02*
Y122957D01*
X711023Y122834D01*
G01X705400Y125000D02*
Y123510D01*
X704725Y122835D01*
G01X721252Y132025D02*
Y134653D01*
X720472Y135433D01*
G01X704725Y122835D02*
X704700Y122810D01*
Y119500D01*
G01X721320Y126495D02*
Y124905D01*
X723391Y122834D01*
X723622D01*
G01X711023D02*
X711700Y122157D01*
Y119500D01*
G01X726122Y126891D02*
Y125334D01*
X723622Y122834D01*
G01X727342Y157715D02*
Y151175D01*
G01D02*
Y145165D01*
G01D02*
Y140466D01*
X726122Y139246D01*
Y126891D01*
G01X723200Y119500D02*
Y122412D01*
X723622Y122834D01*
G01X700200Y125000D02*
Y124609D01*
X698426Y122835D01*
G01X727342Y176315D02*
Y173801D01*
X726770Y173229D01*
G01X727342Y170065D02*
Y172657D01*
X726770Y173229D01*
G01X723922Y126891D02*
Y128832D01*
X723621Y129133D01*
G01X718600Y125000D02*
Y124706D01*
X720472Y122834D01*
G01X713100Y125000D02*
Y123907D01*
X714173Y122834D01*
G01X707600Y125000D02*
Y123109D01*
X707874Y122835D01*
G01X723452Y132025D02*
Y135264D01*
X723621Y135433D01*
G01X723200Y139500D02*
Y141311D01*
X723621Y141732D01*
G01X722142Y170065D02*
Y171749D01*
X723621Y173228D01*
G01X725142Y157715D02*
Y159108D01*
X723621Y160629D01*
G01X725142Y151175D02*
Y152809D01*
X723621Y154330D01*
G01X725142Y145165D02*
Y146510D01*
X723621Y148031D01*
G01X707874Y122835D02*
X708300Y122409D01*
Y119500D01*
G01X723621Y173228D02*
X725142Y171707D01*
Y170065D01*
G01X723621Y154330D02*
X722142Y152851D01*
Y151175D01*
G01X723621Y148031D02*
X722142Y146552D01*
Y145165D01*
G01X714173Y122834D02*
X715300Y121707D01*
Y119500D01*
G01X723000Y164200D02*
Y166308D01*
X723621Y166929D01*
G01X722242Y157715D02*
Y159250D01*
X723621Y160629D01*
G01X717500Y138700D02*
X718700Y137500D01*
X721554D01*
X723621Y135433D01*
G01X719600Y119500D02*
Y121962D01*
X720472Y122834D01*
G01X723621Y129133D02*
X722938D01*
X722500Y128695D01*
X721320D01*
G01X702400Y125000D02*
Y123660D01*
X701575Y122835D01*
G01D02*
X701300Y122560D01*
Y119500D01*
G01X727342Y189185D02*
Y191554D01*
X726770Y192126D01*
G01X729605Y195527D02*
Y194961D01*
X726770Y192126D01*
G01X727342Y182795D02*
Y185255D01*
X726770Y185827D01*
G01X727342Y189185D02*
Y186399D01*
X726770Y185827D01*
G01X727342Y182795D02*
Y180100D01*
X726770Y179528D01*
G01X727342Y176315D02*
Y178956D01*
X726770Y179528D01*
G01X701588Y189806D02*
Y192111D01*
X701574Y192125D01*
G01X722142Y176315D02*
Y178048D01*
X723621Y179527D01*
G01X722142Y182795D02*
Y184347D01*
X723621Y185826D01*
G01X707435Y189777D02*
Y191687D01*
X707873Y192125D01*
G01X723621Y179527D02*
X725142Y178006D01*
Y176315D01*
G01X723621Y185826D02*
X725142Y184305D01*
Y182795D01*
G01X722142Y189185D02*
Y190646D01*
X723621Y192125D01*
G01X725142Y189185D02*
Y190604D01*
X723621Y192125D01*
G01X714601Y195267D02*
Y192553D01*
X714173Y192125D01*
G01X721883Y195408D02*
Y193863D01*
X723621Y192125D01*
G01X726105Y195527D02*
Y194609D01*
X723621Y192125D01*
G01X699602Y194895D02*
Y198078D01*
X698541Y199139D01*
G01X716517Y189273D02*
Y189781D01*
X714173Y192125D01*
G01X707212Y195365D02*
X707873Y194704D01*
Y192125D01*
G01X699602Y194895D02*
Y194757D01*
X701574Y192785D01*
Y192125D01*
G01X800080Y283571D02*
X793962D01*
X793837Y283696D01*
G01X800080Y246171D02*
X795498D01*
G01X800080Y291446D02*
X794087D01*
X793837Y291696D01*
G01X800080Y263886D02*
X805254D01*
G54D37*
X285500Y55518D03*
X281700D03*
X426300Y245700D03*
X644950Y36700D03*
X660300Y150000D03*
X667300Y151100D03*
X689132Y196295D03*
X669000Y246200D03*
X804500Y178530D03*
G54D55*
X367368Y268041D03*
Y264441D03*
X369889Y296241D03*
Y292641D03*
X492132Y300373D03*
Y296773D03*
X469490Y295572D03*
Y291972D03*
X465640Y295572D03*
Y291972D03*
X651430Y174234D03*
Y170634D03*
X772000Y113300D03*
Y109700D03*
G54D73*
X687500Y274750D03*
X683625Y282250D03*
X691375D03*
G54D19*
X46277Y517441D03*
G54D64*
X425845Y231050D03*
X423645D03*
X425845Y233550D03*
X423645D03*
X396100Y226300D03*
X393900D03*
X396900Y230300D03*
X394700D03*
X435267Y273353D03*
X433067D03*
X428400Y257900D03*
X426200D03*
X419600Y254000D03*
X417400D03*
X428400D03*
X426200D03*
X409000Y250900D03*
X406800D03*
X436018Y257827D03*
X433818D03*
X504922Y230291D03*
X502722D03*
X504922Y218500D03*
X502722D03*
X504922Y226350D03*
X502722D03*
X504922Y222450D03*
X502722D03*
X504922Y214576D03*
X502722D03*
X504922Y234219D03*
X502722D03*
X483700Y285200D03*
X481500D03*
X490350Y242150D03*
X488150D03*
X483300Y238100D03*
X481100D03*
X483300Y273600D03*
X481100D03*
X483282Y265195D03*
X481082D03*
X483300Y269650D03*
X481100D03*
X490250Y281500D03*
X488050D03*
X490400Y257900D03*
X488200D03*
X483300Y249950D03*
X481100D03*
X483300Y281550D03*
X481100D03*
X490400Y246000D03*
X488200D03*
X508186Y289438D03*
X505986D03*
X490400Y261950D03*
X488200D03*
X490400Y253900D03*
X488200D03*
X483300Y246000D03*
X481100D03*
X507100Y262500D03*
X504900D03*
X483300Y257800D03*
X481100D03*
X483300Y277600D03*
X481100D03*
X483300Y242100D03*
X481100D03*
X490400Y250000D03*
X488200D03*
X483300Y253900D03*
X481100D03*
X490400Y269700D03*
X488200D03*
X491400Y289300D03*
X489200D03*
X483282Y262695D03*
X481082D03*
X499200Y309020D03*
X497000D03*
X542100Y291500D03*
X539900D03*
X542300Y287400D03*
X540100D03*
X542300Y285200D03*
X540100D03*
X542300Y281300D03*
X540100D03*
X542300Y279100D03*
X540100D03*
X542300Y275200D03*
X540100D03*
X542300Y273000D03*
X540100D03*
X542300Y269100D03*
X540100D03*
X542300Y266900D03*
X540100D03*
X542300Y263100D03*
X540100D03*
X542300Y260900D03*
X540100D03*
X530601Y256167D03*
X528401D03*
X530601Y253967D03*
X528401D03*
X537200Y297600D03*
X535000D03*
X537200Y299800D03*
X535000D03*
X542100Y293700D03*
X539900D03*
X514600Y310000D03*
X512400D03*
X537500Y317200D03*
X535300D03*
X537500Y319400D03*
X535300D03*
X537400Y311200D03*
X535200D03*
X537400Y313400D03*
X535200D03*
X537300Y305100D03*
X535100D03*
X537300Y307300D03*
X535100D03*
X651483Y111296D03*
X649283D03*
X651483Y108996D03*
X649283D03*
X685300Y162630D03*
X683100D03*
X678747Y171175D03*
X676547D03*
X678747Y168975D03*
X676547D03*
X685250Y168930D03*
X683050D03*
X685300Y164830D03*
X683100D03*
X685250Y171130D03*
X683050D03*
X692141Y189723D03*
X689941D03*
X684682Y195495D03*
X682482D03*
X686992Y189743D03*
X684792D03*
X722142Y170065D03*
X719942D03*
X723000Y164200D03*
X720800D03*
X722242Y157715D03*
X720042D03*
X722142Y151175D03*
X719942D03*
X722142Y145165D03*
X719942D03*
X723200Y139500D03*
X721000D03*
X723452Y132025D03*
X721252D03*
X702400Y125000D03*
X700200D03*
X707600D03*
X705400D03*
X713100D03*
X710900D03*
X718600D03*
X716400D03*
X707435Y189777D03*
X705235D03*
X722142Y189185D03*
X719942D03*
X722142Y182795D03*
X719942D03*
X722142Y176315D03*
X719942D03*
X701588Y189806D03*
X699388D03*
G54D46*
X321787Y278970D03*
X325287D03*
X444850Y243879D03*
X438000D03*
X430470D03*
X475500D03*
X459500D03*
X451500D03*
X467600D03*
X645248Y47895D03*
X648748D03*
X652248D03*
X656051Y46793D03*
X660450Y135900D03*
X716517Y189323D03*
X771607Y127493D03*
X800600Y182130D03*
G54D28*
X171738Y432870D03*
X548095Y471383D03*
X609826Y252452D03*
X644800Y252000D03*
G54D92*
G01X708661Y48819D02*
Y47369D01*
G02X707967Y46675I-694J0D01*
G01X704329D01*
X687141Y50017D01*
X671902Y60297D01*
X671740Y61130D01*
X670310Y62094D01*
X669477Y61933D01*
X668047Y62897D01*
X667885Y63730D01*
X666455Y64695D01*
X665622Y64533D01*
X664192Y65498D01*
X664030Y66330D01*
X662600Y67295D01*
X661767Y67133D01*
X660337Y68098D01*
X660175Y68931D01*
X658745Y69895D01*
X657912Y69734D01*
X655249Y71531D01*
X654354Y72135D01*
X651254Y76909D01*
X651113Y77566D01*
Y78738D01*
X651807Y79432D01*
Y79936D01*
G01X708661Y43307D02*
Y44757D01*
G03X707968Y45450I-693J0D01*
G01X704211D01*
X686662Y48861D01*
X674725Y56914D01*
X674724D01*
X667722Y61637D01*
X667723D01*
X653465Y71255D01*
X653462Y71259D01*
X650103Y76431D01*
X649888Y77436D01*
Y78832D01*
X649307Y79413D01*
Y79936D01*
G01X715748Y44095D02*
Y42645D01*
G02X715054Y41951I-694J0D01*
G01X713881D01*
G02X712817Y43015I0J1064D01*
G01Y52484D01*
X712518Y53883D01*
X711325Y55722D01*
X709866Y56516D01*
X706374Y57316D01*
X702627Y56590D01*
X680310Y60924D01*
X671606Y66793D01*
X671444Y67626D01*
X670014Y68590D01*
X669181Y68428D01*
X667750Y69392D01*
X667588Y70225D01*
X666158Y71190D01*
X665325Y71027D01*
X663895Y71992D01*
X663733Y72825D01*
X662302Y73789D01*
X661469Y73627D01*
X659641Y74861D01*
X658040Y77232D01*
X657775Y78593D01*
Y79091D01*
X658580Y79896D01*
G01X715748Y38583D02*
Y40033D01*
G03X715055Y40726I-693J0D01*
G01X713881D01*
G02X711592Y43015I0J2289D01*
G01Y52354D01*
X711367Y53406D01*
X710466Y54794D01*
X709428Y55359D01*
X706353Y56064D01*
X702627Y55342D01*
X679831Y59768D01*
X658761Y73975D01*
X656885Y76753D01*
X656550Y78474D01*
Y79426D01*
X656080Y79896D01*
G01X722834Y48819D02*
Y47369D01*
G02X722140Y46675I-694J0D01*
G01X720967D01*
G02X719904Y47738I0J1063D01*
G01Y49999D01*
X719905D01*
X719208Y53274D01*
X719209D01*
X716110Y58046D01*
X711748Y60879D01*
X705726Y62049D01*
X702419Y61407D01*
X696662Y62526D01*
X696187Y63230D01*
X694494Y63559D01*
X693790Y63084D01*
X692097Y63413D01*
X691623Y64117D01*
X689929Y64446D01*
X689226Y63972D01*
X682968Y65188D01*
X679738Y67485D01*
Y67484D01*
X679597Y68321D01*
X678191Y69320D01*
X677355Y69179D01*
X675949Y70178D01*
X675807Y71015D01*
X674401Y72014D01*
X673565Y71873D01*
X668369Y75567D01*
X668046Y76541D01*
X668045Y76542D01*
X667063Y79491D01*
Y81107D01*
X667550Y81594D01*
G01X722834Y43307D02*
Y44757D01*
G03X722141Y45450I-693J0D01*
G01X720967D01*
G02X718679Y47738I0J2288D01*
G01Y49869D01*
X718678D01*
X718679Y49870D01*
X718057Y52797D01*
X715224Y57160D01*
X711280Y59721D01*
X705726Y60801D01*
X702419Y60159D01*
X682474Y64036D01*
X667333Y74800D01*
X666882Y76155D01*
X665838Y79292D01*
Y81051D01*
X665285Y81604D01*
G01X729921Y44095D02*
Y42645D01*
G02X729227Y41951I-694J0D01*
G01X728054D01*
G02X726990Y43015I0J1064D01*
G01Y52520D01*
X726471Y55182D01*
X724848Y57590D01*
X713749Y65078D01*
X703132Y67142D01*
X702658Y67846D01*
X700964Y68175D01*
X700261Y67701D01*
X698568Y68030D01*
X698093Y68733D01*
X696400Y69062D01*
X695696Y68588D01*
X694003Y68917D01*
X693529Y69621D01*
X691835Y69950D01*
X691132Y69475D01*
X689439Y69805D01*
X688964Y70508D01*
X687271Y70837D01*
X686567Y70363D01*
X684874Y70691D01*
X676299Y76473D01*
X674772Y79730D01*
Y80576D01*
X675326Y81130D01*
G01X729921Y38583D02*
Y40033D01*
G03X729228Y40726I-693J0D01*
G01X728054D01*
G02X725765Y43015I0J2289D01*
G01Y52401D01*
X725315Y54703D01*
X723965Y56708D01*
X713270Y63922D01*
X684395Y69536D01*
X675333Y75646D01*
X673547Y79457D01*
Y80509D01*
X672926Y81130D01*
G01X737007Y48819D02*
Y47369D01*
G02X736313Y46675I-694J0D01*
G01X735140D01*
G02X734076Y47739I0J1064D01*
G01Y54518D01*
X730473Y60063D01*
X726696Y62516D01*
X726519Y63346D01*
X725073Y64285D01*
X724243Y64109D01*
X722796Y65048D01*
X722619Y65878D01*
X721173Y66818D01*
X720343Y66642D01*
X718896Y67581D01*
X718719Y68411D01*
X717273Y69350D01*
X716443Y69174D01*
X714996Y70113D01*
X684422Y76611D01*
X683000Y78623D01*
Y80567D01*
X683563Y81130D01*
G01X737007Y43307D02*
Y44757D01*
G03X736314Y45450I-693J0D01*
G01X735140D01*
G02X732851Y47739I0J2289D01*
G01Y54154D01*
X729587Y59177D01*
X714900Y68714D01*
X714519Y68961D01*
X683698Y75512D01*
X681775Y78233D01*
Y80637D01*
X681283Y81129D01*
G01X744094Y44095D02*
Y42645D01*
G02X743400Y41951I-694J0D01*
G01X742227D01*
G02X741163Y43015I0J1064D01*
G01Y51981D01*
X740527Y54979D01*
X736561Y61087D01*
X736737Y61917D01*
X735797Y63364D01*
X734967Y63540D01*
X734028Y64987D01*
X732592Y65920D01*
X732415Y66750D01*
X730969Y67690D01*
X730139Y67513D01*
X728692Y68453D01*
X728515Y69283D01*
X727069Y70223D01*
X726239Y70046D01*
X720918Y73501D01*
X706112Y76648D01*
X691306Y79794D01*
X690826Y80274D01*
Y80843D01*
X691382Y81399D01*
G01X744094Y38583D02*
Y40033D01*
G03X743401Y40726I-693J0D01*
G01X742227D01*
G02X739938Y43015I0J2289D01*
G01Y51852D01*
X739375Y54502D01*
X733142Y64101D01*
X720441Y72350D01*
X713150Y73899D01*
X705857Y75449D01*
X690696Y78671D01*
X689601Y79766D01*
Y80946D01*
X689149Y81398D01*
G01X660975Y112249D02*
X651102Y102376D01*
Y83532D01*
X651807Y82827D01*
Y82136D01*
G01X649307D02*
Y82749D01*
X649877Y83319D01*
Y84971D01*
X649277Y85571D01*
Y87296D01*
X649877Y87896D01*
Y89621D01*
X649303Y90195D01*
Y91972D01*
X649877Y92546D01*
Y94271D01*
X649277Y94871D01*
Y96596D01*
X649877Y97196D01*
Y98921D01*
X649277Y99521D01*
Y101246D01*
X649877Y101846D01*
Y102884D01*
X653124Y106131D01*
Y106979D01*
X654344Y108199D01*
X655192D01*
X656412Y109419D01*
Y110267D01*
X657632Y111487D01*
X658480D01*
X659806Y112813D01*
X659807D01*
X660108Y113114D01*
G01X662917Y109382D02*
X658945Y105410D01*
Y85856D01*
X657996Y84907D01*
Y83604D01*
X658580Y83020D01*
Y82096D01*
G01X662100Y110298D02*
X660705Y108903D01*
X659857D01*
X658637Y107683D01*
Y106835D01*
X657720Y105918D01*
Y104387D01*
X657120Y103787D01*
Y102062D01*
X657720Y101462D01*
Y99737D01*
X657120Y99137D01*
Y97412D01*
X657720Y96812D01*
Y95087D01*
X657120Y94487D01*
Y92762D01*
X657720Y92162D01*
Y90437D01*
X657120Y89837D01*
Y88112D01*
X657720Y87512D01*
Y86364D01*
X656771Y85415D01*
Y83771D01*
X656080Y83080D01*
Y82096D01*
G01X670652Y114000D02*
Y112686D01*
X666955Y108989D01*
Y84389D01*
X667550Y83794D01*
G01X669427Y114000D02*
Y113195D01*
X669018Y112786D01*
G01X668957Y112725D02*
X668802Y112570D01*
X667546D01*
X666326Y111350D01*
Y110093D01*
X665730Y109497D01*
Y107772D01*
X665130Y107172D01*
Y105447D01*
X665730Y104847D01*
Y103122D01*
X665130Y102522D01*
Y100797D01*
X665730Y100197D01*
Y98472D01*
X665130Y97872D01*
Y96147D01*
X665730Y95547D01*
Y93822D01*
X665130Y93222D01*
Y91497D01*
X665730Y90897D01*
Y89172D01*
X665130Y88572D01*
Y86847D01*
X665730Y86247D01*
Y84249D01*
X665285Y83804D01*
G01X674952Y114219D02*
Y84463D01*
X675326Y84089D01*
Y83330D01*
G01X673727Y114219D02*
Y112752D01*
X672998Y112023D01*
Y110298D01*
X673727Y109569D01*
Y107844D01*
X673127Y107244D01*
Y105519D01*
X673727Y104919D01*
Y103194D01*
X673127Y102594D01*
Y100869D01*
X673727Y100269D01*
Y98544D01*
X673127Y97944D01*
Y96219D01*
X673727Y95619D01*
Y93894D01*
X673127Y93294D01*
Y91569D01*
X673727Y90969D01*
Y89244D01*
X673127Y88644D01*
Y86919D01*
X673727Y86319D01*
Y84692D01*
X672926Y83891D01*
Y83330D01*
G01X681320Y117000D02*
Y112647D01*
X683133Y110834D01*
Y84427D01*
X683563Y83997D01*
Y83330D01*
G01X680095Y117000D02*
Y112139D01*
X681908Y110326D01*
Y108601D01*
X681258Y107951D01*
Y106226D01*
X681908Y105576D01*
Y103851D01*
X681258Y103201D01*
Y101476D01*
X681908Y100826D01*
Y99101D01*
X681258Y98451D01*
Y96726D01*
X681908Y96076D01*
Y94351D01*
X681258Y93701D01*
Y91976D01*
X681908Y91326D01*
Y89601D01*
X681258Y88951D01*
Y87226D01*
X681908Y86576D01*
Y84476D01*
X681283Y83851D01*
Y83329D01*
G01X684098Y116000D02*
Y114956D01*
X687340Y111714D01*
Y105020D01*
X691114Y101246D01*
Y84963D01*
X691382Y84695D01*
Y83599D01*
G01X682873Y116000D02*
Y114448D01*
X683110Y114211D01*
Y113362D01*
X684330Y112142D01*
X685179D01*
X686115Y111206D01*
Y109508D01*
X685515Y108908D01*
Y107183D01*
X686115Y106583D01*
Y104512D01*
X686664Y103963D01*
Y103114D01*
X687884Y101895D01*
X688732D01*
X689889Y100738D01*
Y99494D01*
X689289Y98894D01*
Y97169D01*
X689889Y96569D01*
Y94844D01*
X689289Y94244D01*
Y92519D01*
X689889Y91919D01*
Y90194D01*
X689289Y89594D01*
Y87869D01*
X689889Y87269D01*
Y84923D01*
X689149Y84183D01*
Y83598D01*
G01X701344Y83270D02*
X700925D01*
X700442Y82787D01*
X699452D01*
X698779Y83444D01*
Y100135D01*
X692832Y106082D01*
Y114301D01*
X690626Y116507D01*
Y117632D01*
G01X689401D02*
Y115999D01*
X691607Y113793D01*
Y112068D01*
X691007Y111468D01*
Y109743D01*
X691607Y109143D01*
Y105574D01*
X692827Y104354D01*
Y103506D01*
X694047Y102286D01*
X694895D01*
X697554Y99627D01*
Y82927D01*
X698953Y81562D01*
X700802D01*
X701341Y81023D01*
G01X695967Y111734D02*
Y108680D01*
X701400Y103247D01*
X704812D01*
X707299Y100760D01*
Y87313D01*
X707442Y87169D01*
Y87170D01*
X707946Y86666D01*
X710963Y85391D01*
X711465D01*
X712066Y85992D01*
X712559D01*
G01X694742Y111734D02*
Y108172D01*
X696091Y106823D01*
Y105975D01*
X697311Y104755D01*
X698159D01*
X700892Y102022D01*
X704304D01*
X706074Y100252D01*
Y98527D01*
X705474Y97927D01*
Y96202D01*
X706074Y95602D01*
Y93877D01*
X705474Y93277D01*
Y91552D01*
X706074Y90952D01*
Y86805D01*
X706574Y86304D01*
X707248Y85630D01*
X710714Y84166D01*
X711572D01*
X711978Y83760D01*
X712560D01*
G01X751181Y48819D02*
Y47369D01*
G02X750487Y46675I-694J0D01*
G01X749314D01*
G02X748250Y47739I0J1064D01*
G01Y54322D01*
X748049Y55268D01*
X739435Y68537D01*
X726792Y76746D01*
X716490Y79293D01*
X712713Y80028D01*
X704762Y82628D01*
X704120Y83270D01*
X703544D01*
G01X751181Y43307D02*
Y44757D01*
G03X750488Y45450I-693J0D01*
G01X749314D01*
G02X747025Y47739I0J2289D01*
G01Y54193D01*
X746898Y54791D01*
X738549Y67651D01*
X737102Y68590D01*
X736272Y68414D01*
X734826Y69353D01*
X734649Y70183D01*
X726298Y75606D01*
X721261Y76851D01*
X716226Y78096D01*
X712404Y78840D01*
X704360Y81469D01*
X703987D01*
X703541Y81023D01*
G01X758267Y44095D02*
Y42645D01*
G02X757573Y41951I-694J0D01*
G01X756400D01*
G02X755336Y43015I0J1064D01*
G01Y54548D01*
X754590Y58057D01*
X747226Y69393D01*
X725406Y84110D01*
X718240Y85505D01*
X715899D01*
X715412Y85992D01*
X714759D01*
G01X758267Y38583D02*
Y40033D01*
G03X757574Y40726I-693J0D01*
G01X756400D01*
G02X754111Y43015I0J2289D01*
G01Y54419D01*
X753439Y57580D01*
X746334Y68516D01*
X724927Y82955D01*
X718121Y84280D01*
X715753D01*
X715233Y83760D01*
X714760D01*
G54D83*
G01X452600Y332700D02*
X450950D01*
X449400Y334250D01*
G54D38*
X285500Y59118D03*
X281700D03*
X426300Y249300D03*
X644950Y40300D03*
X660300Y153600D03*
X667300Y154700D03*
X689132Y199895D03*
X669000Y249800D03*
X804500Y182130D03*
G54D56*
X352230Y247771D03*
Y255371D03*
X352228Y275887D03*
Y283487D03*
X352254Y269441D03*
Y261841D03*
X352222Y297541D03*
Y289941D03*
X352214Y303962D03*
Y311562D03*
X625300Y103200D03*
Y110800D03*
X625281Y127708D03*
Y135308D03*
X624026Y267252D03*
Y259652D03*
X605526Y267252D03*
Y259652D03*
X627570Y452930D03*
Y460530D03*
X619200Y441200D03*
Y433600D03*
X626900Y441200D03*
Y433600D03*
X687375Y177704D03*
Y185304D03*
X696761Y177683D03*
Y185283D03*
X639500Y266800D03*
Y259200D03*
X658000Y266800D03*
Y259200D03*
X706195Y177658D03*
Y185258D03*
X783000Y107700D03*
Y115300D03*
X781507Y129393D03*
Y121793D03*
G54D29*
X153038Y443136D03*
X171038D03*
G54D47*
X321787Y275370D03*
X325287D03*
X444850Y240279D03*
X438000D03*
X430470D03*
X475500D03*
X459500D03*
X451500D03*
X467600D03*
X645248Y44295D03*
X648748D03*
X652248D03*
X656051Y43193D03*
X660450Y132300D03*
X716517Y185723D03*
X771607Y123893D03*
X800600Y178530D03*
G54D74*
X673000Y282250D03*
X676875Y274750D03*
X669125D03*
X776000Y85750D03*
X779875Y78250D03*
X772125D03*
X799500Y100750D03*
X803375Y93250D03*
X795625D03*
G54D65*
X407500Y237100D03*
X411398Y231600D03*
Y229400D03*
X395500Y235300D03*
Y233100D03*
X420700Y227400D03*
Y225200D03*
X435600Y227400D03*
Y225200D03*
X430200Y227400D03*
Y225200D03*
X438100Y227400D03*
Y225200D03*
X438500Y235150D03*
Y232950D03*
X445900Y227400D03*
Y225200D03*
X431050Y235150D03*
Y232950D03*
X446400Y235150D03*
Y232950D03*
X427700Y227400D03*
Y225200D03*
X423200Y227400D03*
Y225200D03*
X443900Y235150D03*
Y232950D03*
X436000Y235150D03*
Y232950D03*
X428550Y235150D03*
Y232950D03*
X443400Y227400D03*
Y225200D03*
X412000Y265100D03*
Y262900D03*
X411436Y246100D03*
Y243900D03*
X414500Y265100D03*
Y262900D03*
X407500Y239300D03*
X443700Y284200D03*
Y282000D03*
X430300Y284600D03*
Y282400D03*
X446500Y284200D03*
Y282000D03*
X395500Y243200D03*
Y241000D03*
X435400Y284200D03*
Y282000D03*
X437900Y284200D03*
Y282000D03*
X427635Y241981D03*
Y239781D03*
X428000Y284600D03*
Y282400D03*
X445900Y262350D03*
Y260150D03*
X443500Y271400D03*
Y269200D03*
Y254950D03*
Y252750D03*
X443400Y262350D03*
Y260150D03*
X446000Y271400D03*
Y269200D03*
Y254950D03*
Y252750D03*
X415400Y314500D03*
Y312300D03*
X482750Y227400D03*
Y225200D03*
X462200Y235150D03*
Y232950D03*
X461650Y227400D03*
Y225200D03*
X454340Y235150D03*
Y232950D03*
X467600Y235150D03*
Y232950D03*
X459700Y235150D03*
Y232950D03*
X470100Y235150D03*
Y232950D03*
X496059Y205807D03*
Y203607D03*
X482402Y235178D03*
Y232978D03*
X475400Y235150D03*
Y232950D03*
X469550Y227400D03*
Y225200D03*
X474900Y227400D03*
Y225200D03*
X454150Y227400D03*
Y225200D03*
X459150Y227400D03*
Y225200D03*
X485250Y227400D03*
Y225200D03*
X477400Y227400D03*
Y225200D03*
X451650Y227400D03*
Y225200D03*
X477900Y235150D03*
Y232950D03*
X467050Y227400D03*
Y225200D03*
X451840Y235150D03*
Y232950D03*
X451200Y284100D03*
Y281900D03*
X478400Y285600D03*
Y283400D03*
X474520Y285600D03*
Y283400D03*
X470490Y284400D03*
Y282200D03*
X458100Y284100D03*
Y281900D03*
X465800Y284200D03*
Y282000D03*
X463300Y284200D03*
Y282000D03*
X455800Y284102D03*
Y281902D03*
X453500Y284100D03*
Y281900D03*
X459500Y271400D03*
Y269200D03*
X462000Y271400D03*
Y269200D03*
X451450Y254950D03*
Y252750D03*
X459450Y254950D03*
Y252750D03*
X454550Y262350D03*
Y260150D03*
X454000Y271400D03*
Y269200D03*
X459500Y262350D03*
Y260150D03*
X451500Y271400D03*
Y269200D03*
X453950Y254950D03*
Y252750D03*
X452050Y262350D03*
Y260150D03*
X461950Y254950D03*
Y252750D03*
X462000Y262350D03*
Y260150D03*
X649307Y82136D03*
Y79936D03*
X651807Y82136D03*
Y79936D03*
X656080Y82096D03*
Y79896D03*
X658580Y82096D03*
Y79896D03*
X665285Y83804D03*
Y81604D03*
X667550Y83794D03*
Y81594D03*
X672926Y83330D03*
Y81130D03*
X675326Y83330D03*
Y81130D03*
X681283Y83329D03*
Y81129D03*
X683563Y83330D03*
Y81130D03*
X689149Y83598D03*
Y81398D03*
X691382Y83599D03*
Y81399D03*
X696418Y141404D03*
Y139204D03*
X656875Y173552D03*
Y171352D03*
X683698Y141105D03*
Y138905D03*
X694192Y141403D03*
Y139203D03*
X687898Y141112D03*
Y138912D03*
X690100Y141100D03*
Y138900D03*
X663507Y189280D03*
Y187080D03*
X649027Y191577D03*
Y189377D03*
X656944Y179504D03*
Y177304D03*
X657045Y185173D03*
Y182973D03*
X721320Y128695D03*
Y126495D03*
G54D84*
G01X676547Y171175D02*
X675282D01*
X673229Y173228D01*
G01X676547Y168975D02*
X675275D01*
X673229Y166929D01*
G01X649027Y189377D02*
X650780D01*
X651181Y188976D01*
G01X649027Y191577D02*
X650633D01*
X651181Y192125D01*
G01X692125D02*
Y192275D01*
X689132Y195268D01*
Y196345D01*
G01X727342Y170065D02*
Y167502D01*
X726770Y166930D01*
G54D66*
X433218Y253101D03*
X436818D03*
X472600Y278500D03*
X476200D03*
X605026Y238652D03*
X608626D03*
X647700Y125850D03*
X651300D03*
X697700Y119500D03*
X640700Y234700D03*
X644300D03*
X711700Y119500D03*
X715300D03*
X704700D03*
X708300D03*
X701300D03*
X711001Y195267D03*
X714601D03*
G54D75*
X669700Y366779D03*
X680700D03*
G54D48*
X290425Y297650D03*
X292395D03*
X294360D03*
X296330D03*
X298300D03*
X300270D03*
X302235D03*
X304205D03*
X306175D03*
X308140D03*
X310110D03*
X312080D03*
X314045D03*
X316015D03*
X317985D03*
X319955D03*
X321920D03*
X323890D03*
Y373350D03*
X321920D03*
X319955D03*
X317985D03*
X316015D03*
X314045D03*
X312080D03*
X310110D03*
X308140D03*
X306175D03*
X304205D03*
X302235D03*
X300270D03*
X298300D03*
X296330D03*
X294360D03*
X292395D03*
X290425D03*
X325860Y297650D03*
X327825D03*
X329795D03*
X331765D03*
X333730D03*
X335700D03*
X337670D03*
X339640D03*
X341605D03*
X343575D03*
Y373350D03*
X341605D03*
X339640D03*
X337670D03*
X335700D03*
X333730D03*
X331765D03*
X329795D03*
X327825D03*
X325860D03*
G54D39*
X280800Y141000D03*
X280300Y163000D03*
X280800Y204500D03*
Y224500D03*
X280300Y183000D03*
Y246000D03*
X624326Y252452D03*
X659300Y252000D03*
X725904Y338538D03*
G54D57*
X371698Y341070D03*
X376784Y310847D03*
X419979Y263835D03*
X398230Y331430D03*
X483144Y359195D03*
X450841Y351640D03*
X454341Y356355D03*
X478300Y371800D03*
X524250Y476000D03*
X516750D03*
X574100Y483400D03*
Y487900D03*
X641800Y166000D03*
X679384Y201545D03*
X690050Y236469D03*
X692300Y210200D03*
X678789Y262854D03*
X735100Y97900D03*
X734252Y160315D03*
X757115Y136383D03*
X753800Y169500D03*
X757115Y140433D03*
X754021Y145050D03*
X754300Y160800D03*
X757115Y132181D03*
X706047Y138406D03*
X736879Y151899D03*
X721404Y333538D03*
X791800Y106500D03*
X796807Y130593D03*
X779841Y182831D03*
X787750Y182850D03*
G54D85*
G01X368050Y337200D02*
Y332660D01*
X368600Y332110D01*
Y329035D01*
G01X380721Y332810D02*
Y329953D01*
X376881Y326113D01*
X370677D01*
X368600Y324036D01*
Y320965D01*
G54D49*
X295275Y531496D03*
X531495D03*
G54D58*
X375098Y341070D03*
X380184Y310847D03*
X423379Y263835D03*
X401630Y331430D03*
X486544Y359195D03*
X454241Y351640D03*
X457741Y356355D03*
X481700Y371800D03*
X527650Y476000D03*
X520150D03*
X577500Y483400D03*
Y487900D03*
X645200Y166000D03*
X682784Y201545D03*
X693450Y236469D03*
X695700Y210200D03*
X682189Y262854D03*
X738500Y97900D03*
X737652Y160315D03*
X757200Y169500D03*
X757421Y145050D03*
X757700Y160800D03*
X709447Y138406D03*
X740279Y151899D03*
X724804Y333538D03*
X795200Y106500D03*
X760515Y136383D03*
Y140433D03*
Y132181D03*
X800207Y130593D03*
X783241Y182831D03*
X791150Y182850D03*
G54D76*
X658500Y368750D03*
G54D67*
X401575Y410039D03*
X410433D03*
X419292D03*
X404528Y412795D03*
X413386D03*
X422244D03*
X401575Y425000D03*
X410433D03*
X419292D03*
X407480Y422244D03*
X416339D03*
X425197D03*
X407480Y407284D03*
X416339D03*
X425197D03*
X404528Y427756D03*
X413386D03*
X422244D03*
X401575Y439961D03*
X410433D03*
X419292D03*
X404528Y442717D03*
X413386D03*
X422244D03*
X401575Y454921D03*
X410433D03*
X419292D03*
X404528Y457677D03*
X413386D03*
X422244D03*
X407480Y437205D03*
X416339D03*
X425197D03*
X407480Y452165D03*
X416339D03*
X425197D03*
G54D86*
G01X450200Y322150D02*
Y320279D01*
X448819Y318898D01*
G54D77*
X658500Y371250D03*
G54D59*
X381083Y314895D03*
X402658Y262952D03*
X432789Y267240D03*
X412950Y330250D03*
X440186Y351341D03*
X411420Y335630D03*
X501900Y194800D03*
X490044Y354873D03*
X481800Y367500D03*
Y363400D03*
X498500Y368350D03*
X545695Y480090D03*
X569939Y461261D03*
X574033Y476488D03*
X657713Y166929D03*
X688200Y210200D03*
X672900Y288000D03*
X682189Y268500D03*
X740279Y155899D03*
X716046Y276558D03*
X762570Y81900D03*
X762540Y77810D03*
X762570Y86100D03*
G54D68*
X555355Y470540D03*
X562855Y474415D03*
Y466665D03*
X555550Y484900D03*
X563050Y481025D03*
Y488775D03*
X791750Y78500D03*
X799250Y82375D03*
Y74625D03*
G54D87*
G01X121778Y-377522D02*
X122652Y-376647D01*
X123307Y-375189D01*
X123744Y-373146D01*
X123307Y-371397D01*
X122434Y-370230D01*
X120905Y-369355D01*
X115010D01*
Y-386855D01*
X122215D01*
X123744Y-385689D01*
X124617Y-383938D01*
X125054Y-381897D01*
X124617Y-379855D01*
X123307Y-378105D01*
X121778Y-377522D01*
X115010D01*
G01X134475Y-386855D02*
Y-375189D01*
G01Y-377522D02*
X135567Y-376355D01*
X136659Y-375480D01*
X138187Y-375189D01*
X139278Y-375480D01*
X140589Y-376355D01*
G01X150447Y-392105D02*
X151757Y-392688D01*
X153504Y-392105D01*
X154595Y-390939D01*
X155469Y-389480D01*
X156778Y-384814D01*
X159617Y-375189D01*
G01X152630D02*
X156778Y-384814D01*
G01X176025Y-376647D02*
X174497Y-375480D01*
X173187Y-375189D01*
X171440Y-375772D01*
X170130Y-376938D01*
X169257Y-378980D01*
X169038Y-381022D01*
X169257Y-383064D01*
X170130Y-384814D01*
X171440Y-386272D01*
X173187Y-386855D01*
X174715Y-386272D01*
X176025Y-385105D01*
G01X186757Y-378980D02*
X193744D01*
X193089Y-376938D01*
X191997Y-375772D01*
X190469Y-375189D01*
X188940Y-375480D01*
X187630Y-376355D01*
X186757Y-378397D01*
X186320Y-380147D01*
Y-381897D01*
X186757Y-383647D01*
X187849Y-385397D01*
X189159Y-386563D01*
X190687Y-386855D01*
X192215Y-386272D01*
X193744Y-384522D01*
G01X229835Y-370814D02*
X228525Y-369938D01*
X226997Y-369355D01*
X225250D01*
X223285Y-370230D01*
X221757Y-371688D01*
X220665Y-373439D01*
X219792Y-376355D01*
X219573Y-378980D01*
X220010Y-381605D01*
X220665Y-383355D01*
X221975Y-385105D01*
X223504Y-386272D01*
X225032Y-386855D01*
X226560D01*
X228089Y-386272D01*
X229399Y-385397D01*
X230491Y-384231D01*
G01X246462Y-386855D02*
Y-375189D01*
G01Y-377230D02*
X245589Y-376064D01*
X244278Y-375480D01*
X242750Y-375189D01*
X241222Y-375772D01*
X239912Y-376938D01*
X239038Y-378688D01*
X238602Y-381022D01*
X239038Y-383355D01*
X239912Y-385105D01*
X241222Y-386272D01*
X242750Y-386855D01*
X244278Y-386563D01*
X245589Y-385689D01*
X246462Y-384522D01*
G01X256320Y-386855D02*
Y-375189D01*
G01Y-378105D02*
X257194Y-376647D01*
X258504Y-375480D01*
X260250Y-375189D01*
X261778Y-375480D01*
X263089Y-376647D01*
X263744Y-378688D01*
Y-386855D01*
G01X272947Y-392105D02*
X274257Y-392688D01*
X276004Y-392105D01*
X277095Y-390939D01*
X277969Y-389480D01*
X279278Y-384814D01*
X282117Y-375189D01*
G01X275130D02*
X279278Y-384814D01*
G01X295032Y-386855D02*
X293722Y-386563D01*
X292412Y-385397D01*
X291538Y-383355D01*
X291102Y-381022D01*
X291538Y-378688D01*
X292412Y-376647D01*
X293722Y-375480D01*
X295032Y-375189D01*
X296342Y-375480D01*
X297652Y-376647D01*
X298525Y-378688D01*
X298744Y-381022D01*
X298525Y-383355D01*
X297652Y-385397D01*
X296342Y-386563D01*
X295032Y-386855D01*
G01X308820D02*
Y-375189D01*
G01Y-378105D02*
X309694Y-376647D01*
X311004Y-375480D01*
X312750Y-375189D01*
X314278Y-375480D01*
X315589Y-376647D01*
X316244Y-378688D01*
Y-386855D01*
G01X342947Y-384522D02*
X344694Y-385980D01*
X346659Y-386855D01*
X348405D01*
X350152Y-385980D01*
X351462Y-384522D01*
X352117Y-382480D01*
X351680Y-380439D01*
X350589Y-378688D01*
X348624Y-377522D01*
X346004Y-376938D01*
X344475Y-375772D01*
X343820Y-373730D01*
X344257Y-371688D01*
X345349Y-370230D01*
X346877Y-369355D01*
X348405D01*
X349934Y-369938D01*
X351244Y-371397D01*
G01X369835Y-370814D02*
X368525Y-369938D01*
X366997Y-369355D01*
X365250D01*
X363285Y-370230D01*
X361757Y-371688D01*
X360665Y-373439D01*
X359792Y-376355D01*
X359573Y-378980D01*
X360010Y-381605D01*
X360665Y-383355D01*
X361975Y-385105D01*
X363504Y-386272D01*
X365032Y-386855D01*
X366560D01*
X368089Y-386272D01*
X369399Y-385397D01*
X370491Y-384231D01*
G01X387335Y-370814D02*
X386025Y-369938D01*
X384497Y-369355D01*
X382750D01*
X380785Y-370230D01*
X379257Y-371688D01*
X378165Y-373439D01*
X377292Y-376355D01*
X377073Y-378980D01*
X377510Y-381605D01*
X378165Y-383355D01*
X379475Y-385105D01*
X381004Y-386272D01*
X382532Y-386855D01*
X384060D01*
X385589Y-386272D01*
X386899Y-385397D01*
X387991Y-384231D01*
G01X210605Y-341855D02*
Y-324355D01*
X216282Y-338938D01*
X221959Y-324355D01*
Y-341855D01*
G01X233782D02*
X232472Y-341563D01*
X231162Y-340397D01*
X230288Y-338355D01*
X229852Y-336022D01*
X230288Y-333688D01*
X231162Y-331647D01*
X232472Y-330480D01*
X233782Y-330189D01*
X235092Y-330480D01*
X236402Y-331647D01*
X237275Y-333688D01*
X237494Y-336022D01*
X237275Y-338355D01*
X236402Y-340397D01*
X235092Y-341563D01*
X233782Y-341855D01*
G01X255212Y-324355D02*
Y-341855D01*
G01Y-339231D02*
X254339Y-340689D01*
X253028Y-341563D01*
X251500Y-341855D01*
X249754Y-341272D01*
X248444Y-339814D01*
X247570Y-338064D01*
X247352Y-336022D01*
X247570Y-333980D01*
X248444Y-332230D01*
X249754Y-330772D01*
X251500Y-330189D01*
X253028Y-330480D01*
X254120Y-331064D01*
X255212Y-332230D01*
G01X265507Y-333980D02*
X272494D01*
X271839Y-331938D01*
X270747Y-330772D01*
X269219Y-330189D01*
X267690Y-330480D01*
X266380Y-331355D01*
X265507Y-333397D01*
X265070Y-335147D01*
Y-336897D01*
X265507Y-338647D01*
X266599Y-340397D01*
X267909Y-341563D01*
X269437Y-341855D01*
X270965Y-341272D01*
X272494Y-339522D01*
G01X286282Y-341855D02*
Y-324355D01*
G01X566882Y-386855D02*
Y-369355D01*
X564262Y-372855D01*
G01Y-386855D02*
X569502D01*
G01X580234Y-379564D02*
X581762Y-377522D01*
X583072Y-376355D01*
X584819Y-375772D01*
X586347Y-376355D01*
X587439Y-377522D01*
X588312Y-379272D01*
X588530Y-381313D01*
X588312Y-383064D01*
X587439Y-384814D01*
X586128Y-386272D01*
X584600Y-386855D01*
X582854Y-386272D01*
X581325Y-384522D01*
X580452Y-381897D01*
X580234Y-378980D01*
X580670Y-375189D01*
X581325Y-373146D01*
X582417Y-371105D01*
X583945Y-369647D01*
X585474Y-369355D01*
X587002Y-369938D01*
X588094Y-371397D01*
G01X597079Y-383355D02*
X598388Y-385397D01*
X600135Y-386563D01*
X602100Y-386855D01*
X603847Y-386563D01*
X605594Y-385105D01*
X606685Y-383355D01*
X606904Y-381605D01*
X606467Y-379564D01*
X604939Y-378105D01*
X603410Y-377522D01*
X601445D01*
G01X603410D02*
X604720Y-376647D01*
X605812Y-375189D01*
X606249Y-373439D01*
X605812Y-371688D01*
X604720Y-370230D01*
X602755Y-369355D01*
X600790Y-369647D01*
X598825Y-370814D01*
G01X619382Y-386855D02*
Y-369355D01*
X616762Y-372855D01*
G01Y-386855D02*
X622002D01*
G01X632734Y-379564D02*
X634262Y-377522D01*
X635572Y-376355D01*
X637319Y-375772D01*
X638847Y-376355D01*
X639939Y-377522D01*
X640812Y-379272D01*
X641030Y-381313D01*
X640812Y-383064D01*
X639939Y-384814D01*
X638628Y-386272D01*
X637100Y-386855D01*
X635354Y-386272D01*
X633825Y-384522D01*
X632952Y-381897D01*
X632734Y-378980D01*
X633170Y-375189D01*
X633825Y-373146D01*
X634917Y-371105D01*
X636445Y-369647D01*
X637974Y-369355D01*
X639502Y-369938D01*
X640594Y-371397D01*
G01X553765Y-341855D02*
Y-324355D01*
X559005D01*
X560752Y-325230D01*
X562062Y-327272D01*
X562499Y-329605D01*
X562062Y-331938D01*
X560970Y-333688D01*
X559005Y-334564D01*
X553765D01*
G01X580435Y-325814D02*
X579125Y-324938D01*
X577597Y-324355D01*
X575850D01*
X573885Y-325230D01*
X572357Y-326688D01*
X571265Y-328439D01*
X570392Y-331355D01*
X570173Y-333980D01*
X570610Y-336605D01*
X571265Y-338355D01*
X572575Y-340105D01*
X574104Y-341272D01*
X575632Y-341855D01*
X577160D01*
X578689Y-341272D01*
X579999Y-340397D01*
X581091Y-339231D01*
G01X594878Y-332522D02*
X595752Y-331647D01*
X596407Y-330189D01*
X596844Y-328146D01*
X596407Y-326397D01*
X595534Y-325230D01*
X594005Y-324355D01*
X588110D01*
Y-341855D01*
X595315D01*
X596844Y-340689D01*
X597717Y-338938D01*
X598154Y-336897D01*
X597717Y-334855D01*
X596407Y-333105D01*
X594878Y-332522D01*
X588110D01*
G01X604082Y-347688D02*
X617182D01*
G01X623110Y-341855D02*
Y-324355D01*
X633154Y-341855D01*
Y-324355D01*
G01X645632Y-341855D02*
X643885Y-341563D01*
X642357Y-340397D01*
X641047Y-338647D01*
X640173Y-336605D01*
X639737Y-334272D01*
Y-331938D01*
X640173Y-329605D01*
X641047Y-327563D01*
X642357Y-325814D01*
X643885Y-324647D01*
X645632Y-324355D01*
X647378Y-324647D01*
X648907Y-325814D01*
X650217Y-327563D01*
X651091Y-329605D01*
X651527Y-331938D01*
Y-334272D01*
X651091Y-336605D01*
X650217Y-338647D01*
X648907Y-340397D01*
X647378Y-341563D01*
X645632Y-341855D01*
G01X696473Y-324355D02*
X701932Y-341855D01*
X707391Y-324355D01*
G01X723799Y-341855D02*
X715065D01*
Y-324355D01*
X723799D01*
G01X720305Y-332813D02*
X715065D01*
G01X732565Y-341855D02*
Y-324355D01*
X738024D01*
X739770Y-325230D01*
X740862Y-326397D01*
X741299Y-328730D01*
X740862Y-331064D01*
X739552Y-332522D01*
X738024Y-333397D01*
X732565D01*
G01X738024D02*
X741299Y-341855D01*
G01X754432Y-342438D02*
X753995Y-342147D01*
Y-341563D01*
X754432Y-341272D01*
X754869Y-341563D01*
Y-342147D01*
X754432Y-342438D01*
G01X728182Y-386855D02*
Y-369355D01*
X725562Y-372855D01*
G01Y-386855D02*
X730802D01*
G01X882499Y-369355D02*
Y-386855D01*
X873765D01*
G01X860632D02*
X859104Y-386563D01*
X857357Y-385689D01*
X856265Y-384231D01*
X855829Y-382188D01*
X856265Y-380147D01*
X857575Y-378397D01*
X859540Y-377522D01*
X861724D01*
X863034Y-376938D01*
X864126Y-375480D01*
X864562Y-373439D01*
X863907Y-371397D01*
X862379Y-369938D01*
X860632Y-369355D01*
X858886Y-369938D01*
X857357Y-371397D01*
X856702Y-373439D01*
X857139Y-375480D01*
X858230Y-376938D01*
X859540Y-377522D01*
X861724D01*
X863689Y-378397D01*
X864999Y-380147D01*
X865435Y-382188D01*
X864999Y-384231D01*
X863907Y-385689D01*
X862160Y-386563D01*
X860632Y-386855D01*
G01X830015Y-324355D02*
Y-341855D01*
X838749D01*
G01X855812D02*
Y-330189D01*
G01Y-332230D02*
X854939Y-331064D01*
X853628Y-330480D01*
X852100Y-330189D01*
X850572Y-330772D01*
X849262Y-331938D01*
X848388Y-333688D01*
X847952Y-336022D01*
X848388Y-338355D01*
X849262Y-340105D01*
X850572Y-341272D01*
X852100Y-341855D01*
X853628Y-341563D01*
X854939Y-340689D01*
X855812Y-339522D01*
G01X864797Y-347105D02*
X866107Y-347688D01*
X867854Y-347105D01*
X868945Y-345939D01*
X869819Y-344480D01*
X871128Y-339814D01*
X873967Y-330189D01*
G01X866980D02*
X871128Y-339814D01*
G01X883607Y-333980D02*
X890594D01*
X889939Y-331938D01*
X888847Y-330772D01*
X887319Y-330189D01*
X885790Y-330480D01*
X884480Y-331355D01*
X883607Y-333397D01*
X883170Y-335147D01*
Y-336897D01*
X883607Y-338647D01*
X884699Y-340397D01*
X886009Y-341563D01*
X887537Y-341855D01*
X889065Y-341272D01*
X890594Y-339522D01*
G01X901325Y-341855D02*
Y-330189D01*
G01Y-332522D02*
X902417Y-331355D01*
X903509Y-330480D01*
X905037Y-330189D01*
X906128Y-330480D01*
X907439Y-331355D01*
G01X994432Y-386855D02*
X992685Y-386563D01*
X991157Y-385397D01*
X989847Y-383647D01*
X988973Y-381605D01*
X988537Y-379272D01*
Y-376938D01*
X988973Y-374605D01*
X989847Y-372563D01*
X991157Y-370814D01*
X992685Y-369647D01*
X994432Y-369355D01*
X996178Y-369647D01*
X997707Y-370814D01*
X999017Y-372563D01*
X999891Y-374605D01*
X1000327Y-376938D01*
Y-379272D01*
X999891Y-381605D01*
X999017Y-383647D01*
X997707Y-385397D01*
X996178Y-386563D01*
X994432Y-386855D01*
G01X996178Y-382188D02*
X998799Y-386855D01*
G01X1007129Y-369355D02*
Y-381897D01*
X1008002Y-384522D01*
X1009749Y-386272D01*
X1011932Y-386855D01*
X1014115Y-386272D01*
X1015862Y-384522D01*
X1016735Y-381897D01*
Y-369355D01*
G01X1026812D02*
X1032052D01*
G01X1029432D02*
Y-386855D01*
G01X1026812D02*
X1032052D01*
G01X1041910D02*
Y-369355D01*
X1051954Y-386855D01*
Y-369355D01*
G01X1069235Y-370814D02*
X1067925Y-369938D01*
X1066397Y-369355D01*
X1064650D01*
X1062685Y-370230D01*
X1061157Y-371688D01*
X1060065Y-373439D01*
X1059192Y-376355D01*
X1058973Y-378980D01*
X1059410Y-381605D01*
X1060065Y-383355D01*
X1061375Y-385105D01*
X1062904Y-386272D01*
X1064432Y-386855D01*
X1065960D01*
X1067489Y-386272D01*
X1068799Y-385397D01*
X1069891Y-384231D01*
G01X1081932Y-386855D02*
Y-378980D01*
X1077565Y-369355D01*
G01X1086299D02*
X1081932Y-378980D01*
G01X972129Y-341855D02*
Y-324355D01*
X976495D01*
X978242Y-325230D01*
X979552Y-326397D01*
X980644Y-328146D01*
X981517Y-330189D01*
X981735Y-333105D01*
X981517Y-336022D01*
X980644Y-338064D01*
X979552Y-339814D01*
X978242Y-340980D01*
X976495Y-341855D01*
X972129D01*
G01X991157Y-333980D02*
X998144D01*
X997489Y-331938D01*
X996397Y-330772D01*
X994869Y-330189D01*
X993340Y-330480D01*
X992030Y-331355D01*
X991157Y-333397D01*
X990720Y-335147D01*
Y-336897D01*
X991157Y-338647D01*
X992249Y-340397D01*
X993559Y-341563D01*
X995087Y-341855D01*
X996615Y-341272D01*
X998144Y-339522D01*
G01X1008657Y-339814D02*
X1009749Y-340980D01*
X1011277Y-341855D01*
X1012587D01*
X1013897Y-341272D01*
X1014770Y-340397D01*
X1015207Y-339231D01*
X1014989Y-337480D01*
X1014115Y-336605D01*
X1010185Y-334855D01*
X1009312Y-332813D01*
X1009749Y-331355D01*
X1010622Y-330480D01*
X1011932Y-330189D01*
X1013242Y-330480D01*
X1014552Y-331355D01*
G01X1029432Y-330189D02*
Y-341855D01*
G01Y-325522D02*
X1028995Y-325230D01*
Y-324647D01*
X1029432Y-324355D01*
X1029869Y-324647D01*
Y-325230D01*
X1029432Y-325522D01*
G01X1043875Y-346230D02*
X1045404Y-347397D01*
X1047150Y-347688D01*
X1048678Y-347397D01*
X1049989Y-345939D01*
X1050862Y-343897D01*
Y-330189D01*
G01Y-332522D02*
X1049989Y-331355D01*
X1048678Y-330480D01*
X1047150Y-330189D01*
X1045404Y-330772D01*
X1044312Y-331938D01*
X1043438Y-333980D01*
X1043002Y-336022D01*
X1043220Y-337772D01*
X1044094Y-339814D01*
X1045404Y-341272D01*
X1047150Y-341855D01*
X1048460Y-341563D01*
X1049989Y-340397D01*
X1050862Y-339231D01*
G01X1060720Y-341855D02*
Y-330189D01*
G01Y-333105D02*
X1061594Y-331647D01*
X1062904Y-330480D01*
X1064650Y-330189D01*
X1066178Y-330480D01*
X1067489Y-331647D01*
X1068144Y-333688D01*
Y-341855D01*
G01X1078657Y-333980D02*
X1085644D01*
X1084989Y-331938D01*
X1083897Y-330772D01*
X1082369Y-330189D01*
X1080840Y-330480D01*
X1079530Y-331355D01*
X1078657Y-333397D01*
X1078220Y-335147D01*
Y-336897D01*
X1078657Y-338647D01*
X1079749Y-340397D01*
X1081059Y-341563D01*
X1082587Y-341855D01*
X1084115Y-341272D01*
X1085644Y-339522D01*
G01X1096375Y-341855D02*
Y-330189D01*
G01Y-332522D02*
X1097467Y-331355D01*
X1098559Y-330480D01*
X1100087Y-330189D01*
X1101178Y-330480D01*
X1102489Y-331355D01*
G01X1143132Y-369355D02*
X1141385Y-369938D01*
X1140075Y-371397D01*
X1139202Y-373146D01*
X1138547Y-375480D01*
X1138329Y-378105D01*
X1138547Y-380730D01*
X1139202Y-383064D01*
X1140075Y-384814D01*
X1141385Y-386272D01*
X1143132Y-386855D01*
X1144878Y-386272D01*
X1146189Y-384814D01*
X1147062Y-383064D01*
X1147717Y-380730D01*
X1147935Y-378105D01*
X1147717Y-375480D01*
X1147062Y-373146D01*
X1146189Y-371397D01*
X1144878Y-369938D01*
X1143132Y-369355D01*
G01X1156484Y-379564D02*
X1158012Y-377522D01*
X1159322Y-376355D01*
X1161069Y-375772D01*
X1162597Y-376355D01*
X1163689Y-377522D01*
X1164562Y-379272D01*
X1164780Y-381313D01*
X1164562Y-383064D01*
X1163689Y-384814D01*
X1162378Y-386272D01*
X1160850Y-386855D01*
X1159104Y-386272D01*
X1157575Y-384522D01*
X1156702Y-381897D01*
X1156484Y-378980D01*
X1156920Y-375189D01*
X1157575Y-373146D01*
X1158667Y-371105D01*
X1160195Y-369647D01*
X1161724Y-369355D01*
X1163252Y-369938D01*
X1164344Y-371397D01*
G01X1174202Y-387438D02*
X1182062Y-369355D01*
G01X1191484Y-372272D02*
X1192794Y-370522D01*
X1194322Y-369647D01*
X1196069Y-369355D01*
X1198252Y-369938D01*
X1199780Y-371397D01*
X1200217Y-373146D01*
X1199999Y-374897D01*
X1199125Y-376355D01*
X1194759Y-379272D01*
X1192794Y-381313D01*
X1191484Y-384231D01*
X1191047Y-386855D01*
X1200217D01*
G01X1213132D02*
Y-369355D01*
X1210512Y-372855D01*
G01Y-386855D02*
X1215752D01*
G01X1226702Y-387438D02*
X1234562Y-369355D01*
G01X1243984Y-372272D02*
X1245294Y-370522D01*
X1246822Y-369647D01*
X1248569Y-369355D01*
X1250752Y-369938D01*
X1252280Y-371397D01*
X1252717Y-373146D01*
X1252499Y-374897D01*
X1251625Y-376355D01*
X1247259Y-379272D01*
X1245294Y-381313D01*
X1243984Y-384231D01*
X1243547Y-386855D01*
X1252717D01*
G01X1265632Y-369355D02*
X1263885Y-369938D01*
X1262575Y-371397D01*
X1261702Y-373146D01*
X1261047Y-375480D01*
X1260829Y-378105D01*
X1261047Y-380730D01*
X1261702Y-383064D01*
X1262575Y-384814D01*
X1263885Y-386272D01*
X1265632Y-386855D01*
X1267378Y-386272D01*
X1268689Y-384814D01*
X1269562Y-383064D01*
X1270217Y-380730D01*
X1270435Y-378105D01*
X1270217Y-375480D01*
X1269562Y-373146D01*
X1268689Y-371397D01*
X1267378Y-369938D01*
X1265632Y-369355D01*
G01X1283132Y-386855D02*
Y-369355D01*
X1280512Y-372855D01*
G01Y-386855D02*
X1285752D01*
G01X1300195D02*
X1300632Y-383064D01*
X1301287Y-379855D01*
X1302160Y-376938D01*
X1303252Y-373730D01*
X1304999Y-369355D01*
X1296265D01*
G01X1190829Y-341855D02*
Y-324355D01*
X1195195D01*
X1196942Y-325230D01*
X1198252Y-326397D01*
X1199344Y-328146D01*
X1200217Y-330189D01*
X1200435Y-333105D01*
X1200217Y-336022D01*
X1199344Y-338064D01*
X1198252Y-339814D01*
X1196942Y-340980D01*
X1195195Y-341855D01*
X1190829D01*
G01X1217062D02*
Y-330189D01*
G01Y-332230D02*
X1216189Y-331064D01*
X1214878Y-330480D01*
X1213350Y-330189D01*
X1211822Y-330772D01*
X1210512Y-331938D01*
X1209638Y-333688D01*
X1209202Y-336022D01*
X1209638Y-338355D01*
X1210512Y-340105D01*
X1211822Y-341272D01*
X1213350Y-341855D01*
X1214878Y-341563D01*
X1216189Y-340689D01*
X1217062Y-339522D01*
G01X1230632Y-324355D02*
Y-341855D01*
G01X1227575Y-330189D02*
X1233689D01*
G01X1244857Y-333980D02*
X1251844D01*
X1251189Y-331938D01*
X1250097Y-330772D01*
X1248569Y-330189D01*
X1247040Y-330480D01*
X1245730Y-331355D01*
X1244857Y-333397D01*
X1244420Y-335147D01*
Y-336897D01*
X1244857Y-338647D01*
X1245949Y-340397D01*
X1247259Y-341563D01*
X1248787Y-341855D01*
X1250315Y-341272D01*
X1251844Y-339522D01*
G54D69*
X529450Y485100D03*
X521950Y481225D03*
Y488975D03*
X757650Y91855D03*
Y99605D03*
X765150Y95730D03*
G54D78*
X724380Y291446D03*
Y289476D03*
Y287511D03*
Y285541D03*
Y283571D03*
Y281601D03*
Y279636D03*
Y277666D03*
Y275696D03*
Y273731D03*
Y271761D03*
Y269791D03*
Y267826D03*
Y265856D03*
Y263886D03*
Y261916D03*
Y259951D03*
Y257981D03*
Y256011D03*
Y254046D03*
Y252076D03*
Y250106D03*
Y248141D03*
Y246171D03*
Y244201D03*
Y242231D03*
Y240266D03*
Y238296D03*
X800080D03*
Y240266D03*
Y242231D03*
Y244201D03*
Y246171D03*
Y248141D03*
Y250106D03*
Y252076D03*
Y254046D03*
Y256011D03*
Y257981D03*
Y259951D03*
Y261916D03*
Y263886D03*
Y265856D03*
Y267826D03*
Y269791D03*
Y271761D03*
Y273731D03*
Y275696D03*
Y277666D03*
Y279636D03*
Y281601D03*
Y283571D03*
Y285541D03*
Y287511D03*
Y289476D03*
Y291446D03*
G54D88*
G01X268004Y424361D02*
X269939D01*
X272900Y421400D01*
Y364300D01*
X261358Y352758D01*
X240300D01*
X233527Y345985D01*
X134523D01*
X110508Y370000D01*
X62600D01*
X56700Y364100D01*
Y285600D01*
X35440Y264340D01*
Y239843D01*
X35405Y239808D01*
G01X102679Y391150D02*
X98604Y387075D01*
Y379847D01*
X90757Y372000D01*
X61771D01*
X54700Y364929D01*
Y286429D01*
X32469Y264198D01*
Y250280D01*
G01X237682Y343985D02*
X133694D01*
X109679Y368000D01*
X82976D01*
X78171Y363195D01*
G01X82171D02*
X84080Y365104D01*
X105697D01*
X121506Y349295D01*
G01X237483Y339988D02*
X235486Y341985D01*
X132865D01*
X130097Y344753D01*
X126048D01*
X121506Y349295D01*
G01X129133Y339988D02*
X122265D01*
X100471Y361782D01*
Y361783D01*
X99266Y362988D01*
G01X129133Y339988D02*
X132621Y336500D01*
X230000D01*
G01X103266Y362988D02*
X114258Y351996D01*
G01X233400Y336600D02*
X231500Y338500D01*
X133521D01*
X129983Y342038D01*
X124216D01*
X114258Y351996D01*
G01X230400Y348000D02*
X136800D01*
X114159Y370641D01*
Y389676D01*
X112638Y391197D01*
G01X241556Y340111D02*
X237682Y343985D01*
G01X287350Y351200D02*
Y348100D01*
X298800Y336650D01*
Y311667D01*
X294360Y307227D01*
Y297650D01*
G01X321920D02*
Y301908D01*
X320000Y303828D01*
Y319900D01*
X320833Y320733D01*
Y321441D01*
X320041Y322233D01*
Y322941D01*
X320748Y323648D01*
X321456D01*
X322248Y322856D01*
X322956D01*
X325500Y325400D01*
G01X314241Y308459D02*
Y305231D01*
X317985Y301487D01*
Y297650D01*
G01X314300Y311900D02*
X312200Y309800D01*
Y303400D01*
X312080Y303280D01*
Y297650D01*
G01X308180Y305200D02*
X308140Y305160D01*
Y297650D01*
G01X305628Y320511D02*
Y309580D01*
X303600Y307552D01*
Y302201D01*
X304220Y301581D01*
X304205Y301566D01*
Y297650D01*
G01X301628Y320511D02*
Y311666D01*
X299200Y309238D01*
Y301900D01*
X300270Y300830D01*
Y297650D01*
G01X323890D02*
Y302675D01*
X322000Y304565D01*
Y317900D01*
X325500Y321400D01*
G01X319955Y297650D02*
Y301594D01*
X317900Y303649D01*
Y324351D01*
X314400Y327851D01*
G01X314045Y297650D02*
Y302900D01*
G01X314500Y324251D02*
Y314929D01*
X310200Y310629D01*
Y297740D01*
X310110Y297650D01*
G01X306175D02*
Y301161D01*
X306195Y301181D01*
Y302905D01*
X305600Y303500D01*
Y306213D01*
X308110Y308723D01*
Y311368D01*
X312400Y315658D01*
Y329147D01*
X313853Y330600D01*
X319100D01*
G01X305628Y324511D02*
X303628Y322511D01*
Y310786D01*
X301600Y308758D01*
Y302000D01*
X302245Y301355D01*
Y300081D01*
X302235Y300071D01*
Y297650D01*
G01X283000Y286250D02*
X287500D01*
G01D02*
X295250D01*
X296000Y287000D01*
G01D02*
Y294170D01*
X296330Y294500D01*
Y297650D01*
G01Y373350D02*
Y370630D01*
X290800Y365100D01*
Y352800D01*
X297021Y346579D01*
G01X319550Y347169D02*
X317800D01*
X317300Y347669D01*
Y349908D01*
X317800Y350408D01*
X319900D01*
X320400Y350908D01*
Y351908D01*
X319900Y352408D01*
X317800D01*
X317300Y352908D01*
Y353908D01*
X317800Y354408D01*
X320200D01*
X320700Y354908D01*
Y355908D01*
X320200Y356408D01*
X317800D01*
X317300Y356908D01*
Y357908D01*
X317800Y358408D01*
X322400D01*
X322900Y358908D01*
Y359908D01*
X322400Y360408D01*
X320300D01*
X319800Y360908D01*
Y361908D01*
X320300Y362408D01*
X321800D01*
X322567Y363175D01*
Y367967D01*
X323860Y369260D01*
Y370329D01*
X323890Y370359D01*
Y373350D01*
G01X305147Y354706D02*
Y362647D01*
X310110Y367610D01*
Y368337D01*
X310140Y368367D01*
Y370329D01*
X310110Y370359D01*
Y373350D01*
G01X317985D02*
Y370359D01*
X318015Y370329D01*
Y369785D01*
X318538Y369262D01*
Y366338D01*
X313300Y361100D01*
Y337700D01*
X310900Y335300D01*
X301300D01*
X300800Y334800D01*
Y333500D01*
X301300Y333000D01*
X303700D01*
X304200Y332500D01*
Y331479D01*
X303700Y330979D01*
X301300D01*
X300800Y330479D01*
Y329479D01*
X301300Y328979D01*
X303700D01*
X304300Y328379D01*
Y327000D01*
X304800Y326500D01*
X305800D01*
X306300Y327000D01*
Y332600D01*
X306800Y333100D01*
X307800D01*
X308300Y332600D01*
Y316600D01*
X308800Y316100D01*
X309800D01*
X310300Y316600D01*
Y332600D01*
X310600Y332900D01*
X314200D01*
X314700Y333400D01*
Y334935D01*
X315800Y336035D01*
Y341950D01*
X316050Y342200D01*
G01X287350Y357700D02*
Y364479D01*
X292395Y369524D01*
Y373350D01*
G01X322500Y353700D02*
Y345691D01*
X322000Y345191D01*
X320400D01*
X319900Y344691D01*
Y343691D01*
X320400Y343191D01*
X322000D01*
X322500Y342691D01*
Y341691D01*
X322000Y341191D01*
X320400D01*
X319900Y340691D01*
Y339691D01*
X320400Y339191D01*
X322000D01*
X322500Y338691D01*
Y335400D01*
X321706Y334606D01*
X317200D01*
X316700Y334106D01*
Y333106D01*
X317200Y332606D01*
X322200D01*
X322500Y332306D01*
Y329600D01*
X321500Y328600D01*
X319200D01*
X318700Y328100D01*
Y326700D01*
X319200Y326200D01*
X323000D01*
X325400Y328600D01*
Y333624D01*
X325900Y334124D01*
X327700D01*
X328200Y334624D01*
Y335624D01*
X327700Y336124D01*
X325900D01*
X325400Y336624D01*
Y337624D01*
X325900Y338124D01*
X327700D01*
X328200Y338624D01*
Y339624D01*
X327700Y340124D01*
X325900D01*
X325400Y340624D01*
Y348829D01*
X326502Y349931D01*
Y350637D01*
X324874Y352266D01*
Y352972D01*
X325583Y353681D01*
X326289D01*
X327917Y352052D01*
X328623D01*
X329670Y353099D01*
Y368002D01*
X327825Y369847D01*
Y373350D01*
G01X308140D02*
Y369196D01*
X302662Y363718D01*
Y354700D01*
X302162Y354200D01*
X301162D01*
X300662Y354700D01*
Y364700D01*
X300162Y365200D01*
X299162D01*
X298662Y364700D01*
Y353638D01*
X301500Y350800D01*
Y345441D01*
X302000Y344941D01*
X303000D01*
X303500Y345441D01*
Y351300D01*
X304000Y351800D01*
X305000D01*
X305500Y351300D01*
Y343441D01*
X301500Y339441D01*
Y337500D01*
G01X320650Y336456D02*
X320078Y337028D01*
X319128D01*
X317900Y338256D01*
Y343400D01*
X315300Y346000D01*
Y360271D01*
X320538Y365509D01*
Y366038D01*
X320567Y366067D01*
Y368867D01*
X321920Y370220D01*
Y373350D01*
G01X306060Y337640D02*
X309300Y340880D01*
Y363500D01*
X313400Y367600D01*
Y369100D01*
X314045Y369745D01*
Y373350D01*
G01X310200Y337600D02*
Y338951D01*
X311300Y340051D01*
Y362671D01*
X315400Y366771D01*
Y366900D01*
X316015Y367515D01*
Y373350D01*
G01X327825Y297650D02*
Y302970D01*
X327100Y303695D01*
Y310044D01*
X326600Y310544D01*
X324500D01*
X324000Y311044D01*
Y312044D01*
X324500Y312544D01*
X326600D01*
X327100Y313044D01*
Y314044D01*
X326600Y314544D01*
X324500D01*
X324000Y315044D01*
Y316044D01*
X324500Y316544D01*
X326600D01*
X327100Y317044D01*
Y318800D01*
X328100Y319800D01*
Y331300D01*
G01X325860Y297650D02*
Y302756D01*
X325100Y303516D01*
Y306814D01*
X324100Y307814D01*
G01X316786Y386492D02*
X320256D01*
X321467Y385281D01*
Y383273D01*
G01X319955Y373350D02*
Y378926D01*
X321467Y380438D01*
Y383273D01*
G01X308398Y386479D02*
Y379057D01*
X306175Y376834D01*
Y373350D01*
G01X304205D02*
Y382450D01*
G01X304398Y386479D02*
X294442D01*
X293942Y385979D01*
Y384979D01*
X294442Y384479D01*
X301705D01*
X302205Y383979D01*
Y377095D01*
X302235Y377065D01*
Y373350D01*
G01X292800Y363800D02*
X294069D01*
X300270Y370001D01*
Y373350D01*
G01X298300D02*
Y377805D01*
X300019Y379524D01*
G01X294360Y373350D02*
Y377805D01*
X296079Y379524D01*
G01X312398Y386479D02*
Y383744D01*
X313000Y383142D01*
X314700D01*
X315200Y382642D01*
Y381642D01*
X314700Y381142D01*
X312580D01*
X312080Y380642D01*
Y373350D01*
G01X323448Y405064D02*
X324764D01*
X332040Y412340D01*
X335133D01*
G01X335400Y337400D02*
X336627Y336173D01*
X342300D01*
X342800Y335673D01*
Y334673D01*
X342300Y334173D01*
X335900D01*
X335400Y333673D01*
Y332673D01*
X335900Y332173D01*
X342500D01*
X343000Y331673D01*
Y330673D01*
X342500Y330173D01*
X336800D01*
X336300Y329673D01*
Y328673D01*
X336800Y328173D01*
X342700D01*
X343200Y327673D01*
Y326673D01*
X342700Y326173D01*
X336700D01*
X336200Y325673D01*
Y324673D01*
X336700Y324173D01*
X342500D01*
X343000Y323673D01*
Y322673D01*
X342500Y322173D01*
X336800D01*
X336300Y321673D01*
Y320673D01*
X336800Y320173D01*
X342500D01*
X343000Y319673D01*
Y318673D01*
X342500Y318173D01*
X337200D01*
X336700Y317673D01*
Y316673D01*
X337200Y316173D01*
X340700D01*
X341200Y315673D01*
Y314673D01*
X340700Y314173D01*
X337600D01*
X337100Y313673D01*
Y312673D01*
X337600Y312173D01*
X346000D01*
X346500Y311673D01*
Y310673D01*
X346000Y310173D01*
X338700D01*
X338200Y309673D01*
Y308673D01*
X338700Y308173D01*
X345700D01*
X346200Y307673D01*
Y306673D01*
X345700Y306173D01*
X340573D01*
X339640Y305240D01*
Y297650D01*
G01X337670D02*
Y303354D01*
X335882Y305142D01*
Y309823D01*
G01X327400Y342600D02*
X328408D01*
X330200Y340808D01*
Y329911D01*
X331364Y328747D01*
Y310673D01*
X333730Y308307D01*
Y297650D01*
G01X331026Y303354D02*
Y302441D01*
X331765Y301702D01*
Y297650D01*
G01X329364Y316949D02*
Y313964D01*
X329228Y313828D01*
Y301393D01*
X329795Y300826D01*
Y297650D01*
G01X371160Y320965D02*
Y314500D01*
G01X376734Y310847D02*
X373067D01*
X371160Y312754D01*
Y314500D01*
G01X325200Y365100D02*
Y356400D01*
X325700Y355900D01*
X327170D01*
X327670Y356400D01*
Y367173D01*
X325860Y368983D01*
Y373350D01*
G01X337670D02*
Y369400D01*
X338170Y368900D01*
X345500D01*
X346000Y369400D01*
Y378700D01*
X346500Y379200D01*
X352000D01*
X352500Y378700D01*
Y360600D01*
X352000Y360100D01*
X351000D01*
X350500Y360600D01*
Y376100D01*
X350000Y376600D01*
X348800D01*
X348300Y376100D01*
Y355800D01*
X347800Y355300D01*
X346700D01*
X346200Y355800D01*
Y366200D01*
X345700Y366700D01*
X343800D01*
X343300Y366200D01*
Y355800D01*
X342800Y355300D01*
X340875D01*
X340375Y355800D01*
Y365944D01*
G01X345700Y349773D02*
X349873D01*
X358400Y358300D01*
Y381100D01*
X357900Y381600D01*
X355000D01*
X354500Y381100D01*
Y359000D01*
X353016Y357516D01*
X352308D01*
X351816Y358008D01*
X351108D01*
X350401Y357301D01*
Y356593D01*
X350893Y356101D01*
Y355393D01*
X348800Y353300D01*
X344106D01*
X343506Y352700D01*
Y351500D01*
X343106Y351100D01*
X341906D01*
X341506Y351500D01*
Y352700D01*
X340906Y353300D01*
X336500D01*
X335670Y354130D01*
Y356378D01*
X336170Y356878D01*
X337800D01*
X338300Y357378D01*
Y358378D01*
X337800Y358878D01*
X336170D01*
X335670Y359378D01*
Y360378D01*
X336170Y360878D01*
X337800D01*
X338300Y361378D01*
Y362378D01*
X337800Y362878D01*
X336170D01*
X335670Y363378D01*
Y364378D01*
X336170Y364878D01*
X337800D01*
X338300Y365378D01*
Y366378D01*
X337800Y366878D01*
X336170D01*
X335670Y367378D01*
Y369787D01*
X335700Y369817D01*
Y373350D01*
G01X337600Y349600D02*
X339500D01*
X340000Y349100D01*
X343200D01*
X344600Y347700D01*
X350629D01*
X360400Y357471D01*
Y383224D01*
X359900Y383724D01*
X353200D01*
X352700Y384224D01*
Y385224D01*
X353200Y385724D01*
X359900D01*
X360400Y386224D01*
Y387224D01*
X359900Y387724D01*
X353200D01*
X352700Y388224D01*
Y389224D01*
X353200Y389724D01*
X363200D01*
X363700Y389224D01*
Y357500D01*
X351900Y345700D01*
X343000D01*
X341800Y346900D01*
X335400D01*
X333670Y348630D01*
Y370329D01*
X333730Y370389D01*
Y373350D01*
G01X329795D02*
Y370706D01*
X331670Y368831D01*
Y347053D01*
X332512Y346212D01*
X337124Y341600D01*
X356500D01*
X368800Y353900D01*
Y377900D01*
X368300Y378400D01*
X366200D01*
X365700Y377900D01*
Y356500D01*
X352900Y343700D01*
X340000D01*
X339000Y344700D01*
G01X330000Y345800D02*
Y344100D01*
X332300Y341800D01*
Y332870D01*
X333800Y331370D01*
Y311905D01*
X335882Y309823D01*
G01X381133Y314895D02*
Y311746D01*
X380234Y310847D01*
G01X381133Y314895D02*
Y318367D01*
X386159Y323393D01*
Y327300D01*
G01D02*
Y337080D01*
G01X348596Y337250D02*
Y335710D01*
X351050Y333256D01*
Y330500D01*
G01X347750Y315850D02*
X349764D01*
X351050Y317136D01*
Y319900D01*
G01X352396Y337200D02*
Y335269D01*
X354800Y332865D01*
Y330500D01*
G01X366040Y329035D02*
Y327019D01*
X362862Y323841D01*
Y319462D01*
X359200Y315800D01*
G01X355200D02*
X356315D01*
X358550Y318035D01*
Y319900D01*
G01X371648Y341070D02*
Y335023D01*
G01D02*
Y331988D01*
X371160Y331500D01*
Y329035D01*
G01X363400Y315800D02*
X366040Y318440D01*
Y320965D01*
G01X339640Y373350D02*
Y384140D01*
X344000Y388500D01*
G01X331765Y373350D02*
Y386535D01*
G01X457599Y419642D02*
Y406144D01*
X433839Y382384D01*
X387616D01*
X360000Y410000D01*
G01X445000Y422000D02*
Y403021D01*
X431163Y389184D01*
X393316D01*
X370160Y412340D01*
X335133D01*
G01X407484Y262952D02*
X402708D01*
G01X409449Y259843D02*
Y261974D01*
X408471Y262952D01*
X407484D01*
G01X448819Y287403D02*
X450800Y289384D01*
Y303801D01*
X451999Y305000D01*
X453500D01*
X454777Y306277D01*
Y312557D01*
X452450Y314884D01*
Y321250D01*
X454000Y322800D01*
Y329600D01*
X455800Y331400D01*
Y333850D01*
X453750Y335900D01*
X453050D01*
X452300Y336650D01*
Y337500D01*
G01X442908Y293298D02*
X446859D01*
X448818Y291339D01*
G01X437008Y299213D02*
X438882Y297339D01*
X441568D01*
X443272Y299043D01*
Y301181D01*
X447000Y304909D01*
Y308199D01*
X445725Y309474D01*
X443719D01*
X442913Y310280D01*
Y320866D01*
G01X437008Y291339D02*
X435100Y293247D01*
Y312076D01*
X436206Y313182D01*
X438021D01*
X439335Y314496D01*
Y324152D01*
X440803Y325620D01*
Y333962D01*
X442150Y335309D01*
Y338332D01*
X440740Y339742D01*
Y341194D01*
G01X429134Y295277D02*
Y295275D01*
X431102Y293307D01*
G01Y301181D02*
X431101D01*
X429134Y299214D01*
G01X425197Y299213D02*
X423228Y301182D01*
Y305118D01*
G01X427166Y297245D02*
Y311677D01*
X425432Y313411D01*
X424554D01*
X422810Y315155D01*
Y315604D01*
X421066Y317348D01*
X420617D01*
X419339Y318626D01*
Y327561D01*
X417400Y329500D01*
Y340550D01*
G01X427166Y297245D02*
Y289371D01*
X429134Y287403D01*
G01X421260Y295277D02*
X419292Y297245D01*
G01X401680Y331430D02*
X403700Y329410D01*
Y310600D01*
X405200Y309100D01*
X410500D01*
X411500Y308100D01*
Y302500D01*
X412400Y301600D01*
X418874D01*
X421260Y299214D01*
G01X423221Y293300D02*
X425197Y295276D01*
G01X413115Y323215D02*
Y324850D01*
X411836Y326129D01*
Y329086D01*
X413000Y330250D01*
G01X413386Y311025D02*
Y311514D01*
X411736Y313164D01*
Y321836D01*
X413115Y323215D01*
G01X421500Y344550D02*
X423260D01*
X424500Y343310D01*
Y329229D01*
X425737Y327992D01*
Y325715D01*
G01D02*
Y319438D01*
X425197Y318898D01*
G01X427500Y330650D02*
Y329165D01*
X428227Y328438D01*
Y321489D01*
X427165Y320427D01*
Y316929D01*
G01D02*
X427166D01*
X429134Y314961D01*
G01X436736Y351341D02*
X436894Y351183D01*
Y337996D01*
X437251Y337639D01*
Y335361D01*
X436950Y335060D01*
Y329230D01*
X436894Y329174D01*
Y320978D01*
X435039Y319123D01*
Y316929D01*
G01X429134Y311024D02*
X430672Y312562D01*
X432416D01*
X432428Y312574D01*
X433049D01*
X435039Y314564D01*
Y316929D01*
G01X448300Y337500D02*
X449300D01*
X452000Y334800D01*
X452975D01*
X454551Y333224D01*
Y331752D01*
X452300Y329501D01*
Y327750D01*
X450200Y325650D01*
G01X447300Y340850D02*
Y338500D01*
X448300Y337500D01*
G01X452755Y307087D02*
Y312245D01*
X452100Y312900D01*
X447000D01*
X446500Y313400D01*
Y319700D01*
X447854Y321054D01*
Y323304D01*
X450200Y325650D01*
G01X449400Y330750D02*
X448300Y329650D01*
Y327000D01*
X446700Y325400D01*
Y321753D01*
X444882Y319935D01*
Y318898D01*
G01X445400Y330750D02*
X444600Y329950D01*
Y325100D01*
X442913Y323413D01*
Y320866D01*
G01X440740Y341194D02*
X444100Y344554D01*
Y345000D01*
G01X435200Y330550D02*
Y326767D01*
X430940Y322507D01*
Y317092D01*
X433071Y314961D01*
G01X429134Y303151D02*
Y307039D01*
X431105Y309010D01*
G01X425197Y314961D02*
X423229Y316929D01*
Y320867D01*
G01X421500Y330750D02*
Y329743D01*
X423229Y328014D01*
Y320867D01*
G01X413400Y340550D02*
Y339180D01*
X415173Y337407D01*
Y318855D01*
X417517Y316511D01*
X417966D01*
X419097Y315380D01*
Y314931D01*
X421045Y312983D01*
X421494D01*
X423228Y311249D01*
Y305118D01*
G01X417323Y311024D02*
Y311023D01*
X419291Y309055D01*
G01X431203Y326380D02*
X431496Y326673D01*
Y328496D01*
X433000Y330000D01*
Y332631D01*
X430250Y335381D01*
Y341300D01*
X427500Y344050D01*
G01X431203Y326380D02*
X429618Y324795D01*
Y320337D01*
X429134Y319853D01*
Y318898D01*
G01X427500Y344050D02*
X430333D01*
X430633Y344350D01*
X432900D01*
G01X437008Y311024D02*
Y311023D01*
X438976Y309055D01*
G01X437008Y303150D02*
Y303149D01*
X438976Y301181D01*
G01X437008Y307087D02*
X438977Y305118D01*
X442913D01*
G01X433071Y318898D02*
X434000Y319827D01*
Y322200D01*
G01X401700Y337350D02*
Y340950D01*
G01X391900Y344150D02*
X396000D01*
G01X401700Y340950D02*
Y343221D01*
X400771Y344150D01*
X396000D01*
G01X390550Y326820D02*
Y329732D01*
X392453Y331635D01*
G01X401680Y331430D02*
X399290Y333820D01*
X394638D01*
X392453Y331635D01*
G01X407970Y335630D02*
X406070Y333730D01*
Y328660D01*
X407300Y327430D01*
Y313600D01*
X407900Y313000D01*
X410200D01*
X411800Y311400D01*
Y310000D01*
X412700Y309100D01*
X414300D01*
X415200Y308200D01*
Y306200D01*
X415863Y305537D01*
X418874D01*
X421260Y303151D01*
G01X409100Y340550D02*
Y336760D01*
X407970Y335630D01*
G01X409100Y340550D02*
X407015D01*
X405783Y339318D01*
G01X500000Y200788D02*
X498506D01*
X496828Y199110D01*
G01X498450Y194800D02*
X496828Y196422D01*
Y199110D01*
G01X501950Y194800D02*
X503379D01*
X505776Y197197D01*
Y198689D01*
G01X503937Y200788D02*
X505776Y198949D01*
Y198689D01*
G01X466535Y305118D02*
Y301183D01*
X468504Y299214D01*
G01X480315Y295276D02*
X478839D01*
X477955Y296160D01*
Y301006D01*
G01X521522Y341796D02*
Y341222D01*
X507554Y327254D01*
X503356D01*
X500700Y324598D01*
Y322050D01*
X497613Y318963D01*
Y318255D01*
X496706Y317348D01*
X496257D01*
X493870Y314961D01*
Y306368D01*
X492772Y305270D01*
X487325D01*
X486135Y304080D01*
Y302060D01*
X484392Y300317D01*
Y298681D01*
G01D02*
Y295417D01*
X484252Y295277D01*
G01X476378Y291339D02*
X475905Y291812D01*
Y305405D01*
X479600Y309100D01*
Y310300D01*
G01X468500Y333500D02*
X466725Y331725D01*
Y326693D01*
X465883Y325851D01*
Y321036D01*
X466725Y320194D01*
Y309944D01*
X467618Y309051D01*
X468911D01*
X470541Y307421D01*
Y298100D01*
X471041Y297600D01*
X473700D01*
X474400Y296900D01*
Y293298D01*
X472441Y291339D01*
G01X462663Y323248D02*
Y302866D01*
X460630Y300833D01*
Y299213D01*
G01X454724Y301181D02*
Y294876D01*
X456693Y292907D01*
Y291339D01*
G01X500001Y314961D02*
X501720Y316680D01*
X504180D01*
X506050Y318550D01*
Y320550D01*
X515500Y330000D01*
X516847D01*
X518945Y332098D01*
Y332945D01*
X521500Y335500D01*
X524500D01*
G01X516194Y332572D02*
X515972D01*
X503937Y320537D01*
Y318898D01*
G01X477955Y301006D02*
Y302983D01*
X479972Y305000D01*
X480421D01*
X481865Y306444D01*
Y309803D01*
X481702Y309966D01*
Y311297D01*
X480702Y312297D01*
Y321029D01*
X482450Y322777D01*
Y324000D01*
X484750Y326300D01*
Y327850D01*
X497206Y340306D01*
Y341781D01*
G01X490158Y309055D02*
Y312918D01*
X489576Y313500D01*
Y319250D01*
X490826Y320500D01*
X492950D01*
X493676Y321226D01*
Y327576D01*
X496304Y330204D01*
X504704D01*
X513517Y339017D01*
Y341796D01*
G01X488189Y307087D02*
X490157Y309055D01*
X490158D01*
G01X500300Y328154D02*
X501096Y328950D01*
X506350D01*
X517517Y340117D01*
Y341796D01*
G01X500300Y328154D02*
X496237D01*
X494800Y326717D01*
Y320600D01*
X494075Y319875D01*
Y318654D01*
X491971Y316550D01*
X491522D01*
X490576Y315604D01*
Y314318D01*
X492126Y312768D01*
Y311024D01*
G01X479600Y310300D02*
Y320850D01*
X478300Y322150D01*
Y323800D01*
X479500Y325000D01*
X481100D01*
X483050Y326950D01*
Y328979D01*
X494195Y340124D01*
Y349945D01*
X496100Y351850D01*
G01X451300Y340850D02*
Y338500D01*
X452300Y337500D01*
G01X460000Y340750D02*
Y339591D01*
X458550Y338141D01*
Y323550D01*
X454943Y319943D01*
Y317656D01*
X456693Y315906D01*
Y314961D01*
G01X456550Y337500D02*
X456549Y337501D01*
Y339080D01*
X455900Y339729D01*
Y340750D01*
G01D02*
X460000D01*
G01X460800Y337562D02*
Y335900D01*
X462203Y334497D01*
Y331555D01*
X459874Y329226D01*
Y322674D01*
X456693Y319493D01*
Y318898D01*
G01X464000Y340750D02*
X463988D01*
X460800Y337562D01*
G01X468500Y333500D02*
X470200Y335200D01*
Y342590D01*
X473749Y346139D01*
Y348939D01*
X474500Y349690D01*
Y352860D01*
X475990Y354350D01*
X477400D01*
G01X501400Y336000D02*
X498305Y332905D01*
X494651D01*
X488600Y326854D01*
Y325439D01*
X482702Y319541D01*
Y314318D01*
X484272Y312748D01*
X484721D01*
X485802Y311667D01*
Y306444D01*
X484252Y304894D01*
Y303150D01*
G01X501400Y336000D02*
X505379Y339979D01*
Y341761D01*
G01X497550Y324150D02*
Y322137D01*
X496063Y320650D01*
Y318898D01*
G01X488189Y311024D02*
Y319850D01*
X490142Y321803D01*
Y326981D01*
X494511Y331350D01*
X501850D01*
X506700Y336200D01*
G01D02*
X509517Y339017D01*
Y341796D01*
G01X496000Y336000D02*
X484350Y324350D01*
Y322950D01*
X481702Y320302D01*
Y312798D01*
X482702Y311798D01*
Y310381D01*
X484252Y308831D01*
Y307087D01*
G01X501281Y341761D02*
Y341281D01*
X496000Y336000D01*
G01X502138Y348500D02*
X501227Y349411D01*
Y354336D01*
G01X502200Y360559D02*
Y358204D01*
X501227Y357231D01*
Y354336D01*
G01X496063Y314961D02*
X498002Y316900D01*
X500270D01*
X502387Y319017D01*
Y323244D01*
X503468Y324325D01*
G01X491445Y346908D02*
Y342700D01*
G01D02*
Y340234D01*
X477300Y326089D01*
Y320750D01*
X477928Y320122D01*
Y313528D01*
X476378Y311978D01*
Y311024D01*
G01X474210Y316992D02*
Y315042D01*
X474800Y314452D01*
Y309446D01*
X472441Y307087D01*
G01X474210Y316992D02*
Y319241D01*
X475491Y320522D01*
Y325695D01*
X481132Y331336D01*
Y333064D01*
X486873Y338805D01*
Y346906D01*
G01X462663Y323248D02*
Y324947D01*
X464789Y327073D01*
Y335182D01*
X466438Y336831D01*
Y339188D01*
X468000Y340750D01*
G01X500000Y307088D02*
X502035Y309123D01*
Y311528D01*
X503757Y313250D01*
X510800D01*
X514898Y317348D01*
X516460D01*
X518200Y319088D01*
Y323247D01*
X522553Y327600D01*
X532301D01*
X533947Y329246D01*
Y331750D01*
G01X482618Y339392D02*
Y337330D01*
X481906Y336618D01*
X479067D01*
X477900Y335451D01*
Y333229D01*
X475834Y331163D01*
G01X472463Y329837D02*
X474508D01*
X475834Y331163D01*
G01X478618Y339392D02*
X482618D01*
G01X489600Y367209D02*
Y367190D01*
X487250Y364840D01*
Y360261D01*
X486594Y359605D01*
Y359195D01*
G01X481856Y352656D02*
Y351295D01*
X482745Y350406D01*
X486873D01*
G01X481856Y352656D02*
Y353891D01*
X482838Y354873D01*
X486594D01*
G01D02*
Y359195D01*
G01X472000Y350750D02*
Y350019D01*
X471749Y349768D01*
Y346968D01*
X469031Y344250D01*
X468000D01*
G01X468500Y347500D02*
Y348500D01*
X467900Y349100D01*
Y350750D01*
G01D02*
X468450Y351300D01*
X471450D01*
X472000Y350750D01*
G01X503937Y307087D02*
X505963Y309113D01*
X508464D01*
X510601Y311250D01*
X511630D01*
X515193Y314813D01*
X517678D01*
X520600Y317735D01*
Y321531D01*
X522669Y323600D01*
X538451D01*
X546533Y331682D01*
X547908D01*
G01X541747Y331715D02*
Y330231D01*
X537116Y325600D01*
X523254D01*
X519201Y321547D01*
Y318438D01*
X516576Y315813D01*
X514778D01*
X511215Y312250D01*
X509100D01*
X507874Y311024D01*
G01X472441Y314961D02*
X470290Y317112D01*
Y319750D01*
X468257Y321783D01*
Y323578D01*
G01D02*
Y328607D01*
X474550Y334900D01*
X476200D01*
G01X474577Y339415D02*
Y337778D01*
X476200Y336155D01*
Y334900D01*
G01X506000Y351550D02*
Y348762D01*
X506262Y348500D01*
G01X510000Y351550D02*
Y348638D01*
X510138Y348500D01*
G01X498032Y312992D02*
X500484D01*
X503172Y315680D01*
X504595D01*
X506263Y317348D01*
X508517D01*
X509424Y318255D01*
Y321913D01*
X516298Y328787D01*
X520541D01*
X521354Y329600D01*
X528783D01*
X529947Y330764D01*
Y331750D01*
G01X498032Y312992D02*
X498031D01*
X496063Y311024D01*
G01X472441Y318898D02*
X473265Y319722D01*
Y322929D01*
G01D02*
Y325300D01*
X479640Y331675D01*
Y334674D01*
G01X472600Y310400D02*
X470324D01*
X469700Y311024D01*
X468504D01*
G01X454291Y351640D02*
Y356355D01*
G01X454724Y301181D02*
Y303872D01*
X455652Y304800D01*
X457476D01*
X458752Y306076D01*
Y311728D01*
X457773Y312707D01*
X456286D01*
X455100Y313893D01*
Y315700D01*
X453650Y317150D01*
Y320550D01*
X456248Y323148D01*
Y329748D01*
X457150Y330650D01*
Y334071D01*
X454549Y336672D01*
Y338251D01*
X453400Y339400D01*
Y348700D01*
X454291Y349591D01*
Y351640D01*
G01X510700Y367309D02*
X513237D01*
X522500Y358046D01*
Y355750D01*
G01X506700Y367309D02*
X508950Y365059D01*
X512160D01*
X518500Y358719D01*
Y355750D01*
G01X478350Y367500D02*
Y363400D01*
G01X474200Y367500D02*
X478350D01*
G01X495050Y368350D02*
Y373662D01*
G01D02*
Y377685D01*
X496300Y378935D01*
G01X481750Y371800D02*
X488900D01*
X489500Y371200D01*
G01X524500Y335500D02*
X525100D01*
X529622Y340022D01*
Y341796D01*
G01X552200Y339300D02*
Y343200D01*
X552100Y343300D01*
G01X554000Y348250D02*
Y345200D01*
X552100Y343300D01*
G01X525522Y341796D02*
Y340222D01*
X524174Y338874D01*
X522425D01*
X516194Y332643D01*
Y332572D01*
G01X558000Y348250D02*
Y343850D01*
X557500Y343350D01*
G01X556800Y339300D02*
Y342650D01*
X557500Y343350D01*
G01X533947Y331750D02*
X535968Y333771D01*
Y335284D01*
X536697Y336013D01*
Y339813D01*
X534100Y342410D01*
G01X536200Y351350D02*
Y348300D01*
G01X540200Y351350D02*
Y348300D01*
G01X549200Y351350D02*
Y349200D01*
X550100Y348300D01*
G01X545200Y351350D02*
Y349200D01*
X546100Y348300D01*
G01X547927Y342199D02*
X550200Y339926D01*
Y338471D01*
X550712Y337959D01*
Y334486D01*
X547908Y331682D01*
G01X539446Y342347D02*
X540686D01*
X544497Y338536D01*
Y332922D01*
X543290Y331715D01*
X541747D01*
G01X521914Y332907D02*
X522321Y332500D01*
X529197D01*
X529947Y331750D01*
G01X532050Y476200D02*
Y479350D01*
X530175Y481225D01*
X521950D01*
G01X527700Y476000D02*
X531850D01*
X532050Y476200D01*
G01X548295Y471383D02*
Y469040D01*
X547812Y468557D01*
Y464771D01*
G01X545745Y480090D02*
Y476024D01*
X548295Y473474D01*
Y471383D01*
G01X550100Y479850D02*
X552050D01*
X553900Y478000D01*
Y471995D01*
X555355Y470540D01*
G01X545745Y480090D02*
X549860D01*
X550100Y479850D01*
G01X569400Y483400D02*
X574050D01*
G01X555550Y484900D02*
X565300D01*
X566800Y483400D01*
X569400D01*
G01X570583Y476488D02*
Y473239D01*
X569402Y472058D01*
G01X562855Y474415D02*
X565212Y472058D01*
X569402D01*
G01X562460Y457580D02*
X562983D01*
X566489Y461086D01*
Y461261D01*
G01X557750Y461260D02*
Y465250D01*
X559165Y466665D01*
X562855D01*
G01X561657Y461261D02*
X561656Y461260D01*
X557750D01*
G01X561657Y461261D02*
X566489D01*
G01X540140Y489830D02*
X538308D01*
X533578Y485100D01*
X529450D01*
G01X540140Y489830D02*
X541320D01*
X541710Y489440D01*
X549400D01*
G01X563050Y488775D02*
X550065D01*
X549400Y489440D01*
G01X644710Y22817D02*
X638683D01*
X633803Y27697D01*
Y27749D01*
G01D02*
X632013Y29539D01*
X628474D01*
X626786Y31227D01*
G01X637003Y62259D02*
X633009D01*
X633000Y62250D01*
G01X632300Y154650D02*
X636630D01*
G01X632300Y158150D02*
X635150D01*
X638603Y161603D01*
X645729D01*
G01X637343Y171335D02*
X634794Y173884D01*
Y190106D01*
X626400Y198500D01*
G01X624000Y203250D02*
Y196700D01*
X633500Y187200D01*
Y172844D01*
X636844Y169500D01*
X640600D01*
X642000Y168100D01*
X647459D01*
X653832Y161727D01*
X656230D01*
X656878Y161079D01*
G01X628000Y203250D02*
Y200100D01*
X626400Y198500D01*
G01X632000Y203250D02*
Y198800D01*
X631700Y198500D01*
G01X637343Y174835D02*
X636340Y175838D01*
Y193860D01*
X631700Y198500D01*
G01X801728Y304572D02*
X799919Y306381D01*
X736812D01*
X728191Y297760D01*
X658534D01*
X633838Y322456D01*
X611606D01*
G01D02*
X599744D01*
X597450Y324750D01*
G01X801853Y300515D02*
X797988Y304380D01*
X737640D01*
X729020Y295760D01*
X657705D01*
X633481Y319984D01*
X623969D01*
G01D02*
X598216D01*
X597450Y320750D01*
G01X574050Y483400D02*
Y487900D01*
G01X664301Y49998D02*
Y51899D01*
X653941Y62259D01*
X646000D01*
G01X664301Y40104D02*
Y49998D01*
G01X658116Y36660D02*
Y38516D01*
X659850Y40250D01*
Y42534D01*
G01D02*
Y46750D01*
G01X656051Y46743D02*
X659843D01*
X659850Y46750D01*
G01X644710Y26317D02*
X640683D01*
X639900Y27100D01*
G01D02*
Y29243D01*
X640416Y29759D01*
Y31609D01*
G01X651616Y31540D02*
Y28627D01*
X650876Y27887D01*
X646280D01*
X644710Y26317D01*
G01Y22817D02*
X647593Y25700D01*
X658152D01*
X662200Y29748D01*
Y33500D01*
X661600Y34100D01*
X658116D01*
G01X641003Y62259D02*
X646000D01*
G01X637003D02*
X641003D01*
G01X651722Y198588D02*
X654509Y195801D01*
Y190631D01*
X658855Y186285D01*
Y172592D01*
X660629Y170818D01*
Y170078D01*
G01X657113Y198415D02*
X655700Y197002D01*
Y191200D01*
X660629Y186271D01*
Y173227D01*
G01X707873Y129133D02*
X705223Y126483D01*
X696824D01*
X695770Y125429D01*
G01X650936Y160874D02*
Y163208D01*
X648144Y166000D01*
X645250D01*
G01X654330Y157480D02*
X650936Y160874D01*
G01X651181Y154330D02*
X648035D01*
G01X661644Y164498D02*
Y165369D01*
X660084Y166929D01*
X657763D01*
G01X661644Y164498D02*
Y161644D01*
X660630Y160630D01*
G01X636630Y154650D02*
X638552D01*
X640120Y156218D01*
X640775D01*
G01X645729Y161603D02*
X647272D01*
X648031Y160844D01*
Y157480D01*
G01X656878Y161079D02*
X657480Y160477D01*
Y154330D01*
G01X646004Y179768D02*
Y177639D01*
X646788Y176855D01*
Y175134D01*
X644882Y173228D01*
G01Y170078D02*
X637910Y177050D01*
Y197590D01*
X637000Y198500D01*
G01X650722Y183439D02*
Y177272D01*
X648031Y174581D01*
Y170078D01*
G01X693674Y132295D02*
Y130404D01*
X696595Y127483D01*
X703073D01*
X704723Y129133D01*
G01X679452Y209815D02*
X680425Y208842D01*
Y205984D01*
G01X679334Y201545D02*
X680425Y202636D01*
Y205984D01*
G01X651722Y198588D02*
X656000Y202866D01*
Y203250D01*
G01X660000D02*
Y201302D01*
X657113Y198415D01*
G01X694087Y201724D02*
Y199613D01*
X695275Y198425D01*
G01X690207Y205597D02*
Y202459D01*
X692125Y200541D01*
Y198423D01*
G01X648000Y203250D02*
Y200665D01*
X647700Y200365D01*
Y198000D01*
X647067Y197367D01*
Y188300D01*
X648300Y187067D01*
Y184500D01*
X647067Y183267D01*
Y180831D01*
X646004Y179768D01*
G01X644882Y176378D02*
X643272Y177988D01*
Y183172D01*
X646000Y185900D01*
G01D02*
Y201250D01*
X644000Y203250D01*
G01X636000D02*
Y199500D01*
X637000Y198500D01*
G01X652000Y203250D02*
X648700Y199950D01*
Y197800D01*
X653300Y193200D01*
Y188000D01*
X650722Y185422D01*
Y183439D01*
G01X642300Y198500D02*
Y191610D01*
X639206Y188516D01*
Y178903D01*
X640509Y177600D01*
G01X642300Y198500D02*
Y200950D01*
X640000Y203250D01*
G01X695600Y244354D02*
X693500Y242254D01*
Y236469D01*
G01X690000D02*
X684696D01*
G01D02*
X681290D01*
X680350Y237409D01*
Y241121D01*
X678739Y242732D01*
Y245084D01*
G01X695383Y266855D02*
Y273959D01*
X690846Y278496D01*
X683969D01*
X680223Y274750D01*
X676875D01*
G01X691887Y264427D02*
X690754D01*
X689181Y262854D01*
X686982D01*
G01X682239D02*
Y258900D01*
X682489Y258650D01*
Y255684D01*
G01X686982Y262854D02*
X682239D01*
G01X672950Y288000D02*
Y282300D01*
X673000Y282250D01*
G01X672950Y288000D02*
X673280Y288330D01*
X678720D01*
G01D02*
X682625D01*
X683625Y287330D01*
Y282250D01*
G01X682239Y268500D02*
Y269489D01*
X687500Y274750D01*
G01X686912Y268500D02*
X682239D01*
G01X686912D02*
X689870D01*
X690443Y267927D01*
X691887D01*
G01X674989Y255684D02*
Y251804D01*
X676638Y250155D01*
X689468D01*
G01D02*
X694216D01*
X700600Y256539D01*
G01X672131Y383133D02*
X672627D01*
X675127Y385633D01*
X676531D01*
G01D02*
X679567D01*
X680300Y384900D01*
G01X725600Y103600D02*
X724517D01*
X722673Y105444D01*
G01X739900Y112500D02*
X739100D01*
X736785Y110185D01*
G01X737800Y106525D02*
X739275D01*
X742700Y103100D01*
G01X719500Y102900D02*
X717300Y105100D01*
Y109543D01*
X717197Y109646D01*
G01X726100Y107200D02*
Y107041D01*
X730200Y102941D01*
Y98200D01*
G01X734709Y106595D02*
Y105391D01*
X737100Y103000D01*
G01X707874Y116535D02*
Y114926D01*
X708300Y114500D01*
Y113300D01*
G01X731000Y106315D02*
Y109900D01*
X734500Y113400D01*
G01X715100Y107300D02*
Y110000D01*
X716200Y111100D01*
Y113093D01*
X714408Y114885D01*
X712673D01*
X711023Y116535D01*
G01X719000Y112700D02*
X716900Y114800D01*
X715908D01*
X714173Y116535D01*
G01X724200Y110700D02*
Y111600D01*
X720914Y114886D01*
X719789D01*
X718140Y116535D01*
X717322D01*
G01X734212Y109995D02*
X736032Y108175D01*
X741435D01*
X741960Y108700D01*
X745700D01*
G01X761650Y89937D02*
X760715Y89002D01*
X754401D01*
X748303Y95100D01*
X728613D01*
X727101Y96612D01*
Y98989D01*
X725943Y100147D01*
G01X729400Y111800D02*
X729100Y111500D01*
Y105600D01*
X735050Y99650D01*
Y97900D01*
G01X729400Y111800D02*
Y113800D01*
X728400Y114800D01*
X723000D01*
X721264Y116536D01*
X720473D01*
G01X703600Y110600D02*
Y115411D01*
X704725Y116536D01*
G01X719010Y107281D02*
Y106590D01*
X722300Y103300D01*
Y99400D01*
X724600Y97100D01*
G01X707649Y110002D02*
X709702D01*
X712200Y112500D01*
X713700D01*
G01X710517Y106823D02*
X714142Y103198D01*
Y100329D01*
X717087Y97384D01*
G01X757650Y91855D02*
Y94530D01*
X764100Y100980D01*
Y115200D01*
X765900Y117000D01*
Y119700D01*
G01X762620Y86100D02*
X765530Y89010D01*
Y90783D01*
X764458Y91855D01*
X757650D01*
G01X759090Y77810D02*
X757787Y79113D01*
X750466D01*
X747022Y82557D01*
X741621D01*
X733664Y90514D01*
X725770Y90525D01*
X718714D01*
X712725Y96514D01*
Y102843D01*
X710466Y105102D01*
X702798D01*
X701900Y106000D01*
G01X767359Y82076D02*
Y76729D01*
X766125Y75495D01*
X761455D01*
X759140Y77810D01*
X759090D01*
G01X701900Y106000D02*
X701263Y106637D01*
Y109637D01*
X700700Y110200D01*
Y115661D01*
X701575Y116536D01*
G01X704849Y107385D02*
X705414Y107950D01*
X708181D01*
X708892Y108661D01*
X711539D01*
X712928Y107272D01*
Y106406D01*
X720744Y98590D01*
Y92427D01*
G01X732579Y152616D02*
X733296Y151899D01*
X736829D01*
G01X729921Y157480D02*
X732161Y155240D01*
Y153034D01*
X732579Y152616D01*
G01X736829Y151899D02*
Y155899D01*
G01X744222Y120527D02*
X740074D01*
X739952Y120649D01*
G01X740952Y126815D02*
X746615D01*
X747200Y127400D01*
G01X743100Y114700D02*
X747600D01*
X747700Y114800D01*
G01X737352Y145885D02*
X740885D01*
X741500Y146500D01*
G01X738200Y117600D02*
X732006D01*
X726771Y122835D01*
G01X733600Y120500D02*
X732255D01*
X729921Y122834D01*
G01X737702Y128565D02*
Y126102D01*
X736800Y125200D01*
G01X742700Y130600D02*
X737307D01*
X735310Y132597D01*
X730235D01*
X729921Y132283D01*
G01Y129134D02*
X731022Y130235D01*
X733372D01*
G01X726771Y163779D02*
X728737Y165745D01*
X731920D01*
X732385Y165280D01*
X735488D01*
X736730Y166522D01*
G01X741754Y134617D02*
X746383D01*
X746400Y134600D01*
G01X729921Y135433D02*
X736467D01*
X738000Y133900D01*
G01X739622Y137008D02*
X741308D01*
X743400Y139100D01*
G01X729921Y138582D02*
X733882D01*
X734500Y139200D01*
G01X729921Y144882D02*
X732382D01*
X733500Y146000D01*
G01X723622Y116535D02*
X726235D01*
X727700Y118000D01*
G01X699999Y132427D02*
Y130708D01*
X701574Y129133D01*
G01X709497Y138406D02*
X710294D01*
X713500Y135200D01*
G01X707861Y133930D02*
Y136770D01*
X709497Y138406D01*
G01X707861Y133930D02*
Y132294D01*
X711022Y129133D01*
G01X715490Y131490D02*
X714172Y130172D01*
Y129133D01*
G01X715490Y131490D02*
X717500Y133500D01*
Y135200D01*
G01X752500Y127500D02*
X748000Y123000D01*
X732905D01*
X729921Y125984D01*
G01X757065Y132181D02*
Y132065D01*
X752500Y127500D01*
G01X716040Y176322D02*
X714117D01*
X711023Y173228D01*
G01X737315Y177952D02*
X736368D01*
X733792Y175376D01*
G01X754250Y160800D02*
X749533D01*
G01D02*
X747550D01*
X746750Y160000D01*
Y157700D01*
G01X749500Y145050D02*
X747450D01*
X742769Y149731D01*
X731621D01*
X729921Y148031D01*
G01X753971Y145050D02*
X749500D01*
G01X729921Y141732D02*
X731571D01*
X732167Y142328D01*
X746622D01*
X747950Y141000D01*
X750000D01*
G01D02*
X752050D01*
X752617Y140433D01*
X757065D01*
G01X753750Y169500D02*
X750500D01*
X748000Y167000D01*
G01X729921Y163779D02*
X744779D01*
X748000Y167000D01*
G01X750550Y135200D02*
X752400D01*
X753583Y136383D01*
X757065D01*
G01X734202Y160315D02*
X733888Y160629D01*
X729921D01*
G01X715467Y210507D02*
X715300Y210674D01*
Y214400D01*
G01X724380Y242231D02*
X729407D01*
X734611Y237027D01*
X760981D01*
X761481Y237527D01*
Y238527D01*
X760981Y239027D01*
X735509D01*
X735009Y239527D01*
Y240527D01*
X735509Y241027D01*
X759558D01*
G01X742978Y206202D02*
Y204180D01*
X745485Y201673D01*
G01X740352Y180115D02*
X743867D01*
X745778Y178204D01*
G01X729920Y185827D02*
X732639D01*
X734043Y187231D01*
G01X743752Y187115D02*
X746189Y189552D01*
X746691D01*
G01X742502Y182715D02*
X744586D01*
X745659Y183788D01*
G01X724380Y240266D02*
X728543D01*
X733782Y235027D01*
X788433D01*
X790714Y237308D01*
G01X733070Y179527D02*
X735307Y181764D01*
X736078D01*
G01X720357Y207104D02*
X721734Y205727D01*
X725855D01*
X726032Y205904D01*
G01X714173Y198425D02*
X710687Y201911D01*
Y202564D01*
G01X703290Y205505D02*
X706737D01*
G01X698541Y202639D02*
Y204078D01*
X699968Y205505D01*
X703290D01*
G01X710800Y214550D02*
Y207533D01*
X711310Y207023D01*
G01X719700Y214550D02*
X717956Y212806D01*
Y209097D01*
X714195Y205336D01*
Y201596D01*
X714173Y201574D01*
G01X718330Y205172D02*
X718928D01*
X721500Y202600D01*
G01X716096Y276558D02*
Y272396D01*
G01D02*
Y269555D01*
X717825Y267826D01*
X724380D01*
G01X800080Y287511D02*
X796620D01*
X794651Y289480D01*
X741169D01*
X739300Y287611D01*
G01X751693Y255540D02*
X749638D01*
X749138Y256040D01*
Y256771D01*
X748638Y257271D01*
X747638D01*
X747138Y256771D01*
Y256040D01*
X746638Y255540D01*
X745638D01*
X745138Y256040D01*
Y256771D01*
X744638Y257271D01*
X743638D01*
X743138Y256771D01*
Y256040D01*
X742638Y255540D01*
X741638D01*
X741138Y256040D01*
Y256771D01*
X740638Y257271D01*
X739638D01*
X739138Y256771D01*
Y256040D01*
X738638Y255540D01*
X737638D01*
X737138Y256040D01*
Y256771D01*
X736638Y257271D01*
X735638D01*
X735138Y256771D01*
Y256040D01*
X734638Y255540D01*
X731611D01*
X730117Y254046D01*
X724380D01*
G01X743507Y251685D02*
X742464Y252728D01*
X731195D01*
X730543Y252076D01*
X724380D01*
G01Y250106D02*
X732735D01*
X733529Y249312D01*
X745843D01*
X746343Y249812D01*
Y252917D01*
X746843Y253417D01*
X747843D01*
X748343Y252917D01*
Y250770D01*
X748843Y250270D01*
X749843D01*
X750343Y250770D01*
Y252917D01*
X750843Y253417D01*
X751843D01*
X752343Y252917D01*
Y250916D01*
X752843Y250416D01*
X753843D01*
X754343Y250916D01*
Y252917D01*
X754843Y253417D01*
X759320D01*
X761484Y255581D01*
G01X747558Y247274D02*
X732689D01*
X731822Y248141D01*
X724380D01*
G01Y246171D02*
X731239D01*
X732213Y245197D01*
X749182D01*
X749682Y245697D01*
Y247623D01*
X750182Y248123D01*
X751182D01*
X751682Y247623D01*
Y245789D01*
X752182Y245289D01*
X753182D01*
X753682Y245789D01*
Y247582D01*
X754182Y248082D01*
X755182D01*
X755682Y247582D01*
Y245893D01*
X756182Y245393D01*
X757182D01*
X757682Y245893D01*
Y249067D01*
X758182Y249567D01*
X759470D01*
X761484Y251581D01*
G01X780837Y240885D02*
Y237724D01*
X780337Y237224D01*
X768175D01*
X767675Y237724D01*
Y241498D01*
X767175Y241998D01*
X766175D01*
X765675Y241498D01*
Y237850D01*
X765175Y237350D01*
X764175D01*
X763675Y237850D01*
Y242665D01*
X763175Y243165D01*
X731437D01*
X730401Y244201D01*
X724380D01*
G01Y273731D02*
X729107D01*
X731851Y270987D01*
X771396D01*
X774637Y267746D01*
G01X724380Y271761D02*
X728059D01*
X730833Y268987D01*
X769396D01*
X770637Y267746D01*
G01X731300Y287611D02*
X731200Y287511D01*
X724380D01*
G01X761638Y259635D02*
X759417Y261856D01*
X732226D01*
X728351Y257981D01*
X724380D01*
G01X774637Y259746D02*
X768144D01*
X764034Y263856D01*
X731397D01*
X727492Y259951D01*
X724380D01*
G01Y265856D02*
X765100D01*
X767210Y263746D01*
X774637D01*
G01X724380Y285541D02*
X733230D01*
X735300Y287611D01*
G01X724380Y283571D02*
X731318D01*
G01X724380Y281601D02*
X733348D01*
X735318Y283571D01*
G01X731155Y279636D02*
X724380D01*
G01Y277666D02*
X731751D01*
X733696Y279611D01*
X735358D01*
X739318Y283571D01*
G01X724380Y275696D02*
X729664D01*
X730864Y274496D01*
X733438D01*
X734638Y275696D01*
G01X751693Y259540D02*
X732739D01*
X729210Y256011D01*
X724380D01*
G01X800080Y248141D02*
X770303D01*
X763485Y254959D01*
Y256197D01*
X762004Y257678D01*
X757555D01*
X755693Y259540D01*
G01X724380Y263886D02*
X714616D01*
X707377Y256647D01*
X704708D01*
G01Y252647D02*
X710693D01*
X719962Y261916D01*
X724380D01*
G01X704708Y260647D02*
X700600Y256539D01*
G01X739680Y429140D02*
Y423900D01*
G01X779875Y78250D02*
X784280D01*
X785050Y79020D01*
Y79670D01*
G01D02*
Y83950D01*
X785350Y84250D01*
G01X791750Y78500D02*
X791000D01*
X789500Y80000D01*
Y82000D01*
X787250Y84250D01*
X785350D01*
G01X788287Y86087D02*
Y87587D01*
X790100Y89400D01*
X791700D01*
X792800Y90500D01*
Y95800D01*
X794200Y97200D01*
X801800D01*
X803375Y95625D01*
Y93250D01*
G01X799500Y100750D02*
X792250D01*
X790000Y98500D01*
G01X785350Y95250D02*
X787250D01*
X790000Y92500D01*
G01X776500Y98500D02*
X771371D01*
G01X765150Y95730D02*
X767920Y98500D01*
X771371D01*
G01X781000Y95250D02*
X779250D01*
X776500Y92500D01*
G01X776000Y85750D02*
X775453D01*
X772398Y88805D01*
X769475D01*
X766694Y86024D01*
G01X762590Y77810D02*
Y81870D01*
X762620Y81900D01*
G01X766694Y86024D02*
X762620Y81950D01*
Y81900D01*
G01X763560Y59820D02*
X773115Y69375D01*
X788780D01*
X799250Y79845D01*
Y82375D01*
G01X800000Y145240D02*
Y152000D01*
G01X798500Y140850D02*
Y142504D01*
X800000Y144004D01*
Y145240D01*
G01X802696Y140850D02*
X798500D01*
G01X795000Y152000D02*
Y148401D01*
X793378Y146779D01*
Y145309D01*
G01D02*
Y143025D01*
X794500Y141903D01*
Y140850D01*
G01D02*
X790500D01*
G01X790000Y152000D02*
Y149597D01*
X785756Y145353D01*
G01D02*
X782500Y142097D01*
Y140850D01*
G01D02*
X786500D01*
G01X790000Y172000D02*
Y178300D01*
X790050Y178350D01*
G01X785000Y172000D02*
Y175750D01*
X782850Y177900D01*
Y178350D01*
G01X795000Y172000D02*
Y178100D01*
X795450Y178550D01*
G01X765900Y119700D02*
Y131800D01*
X768900Y134800D01*
G01X791200Y182850D02*
Y179500D01*
X790050Y178350D01*
G01X783291Y182831D02*
X782850Y182390D01*
Y178350D01*
G01X796110Y182850D02*
Y179210D01*
X795450Y178550D01*
G01X787700Y182850D02*
Y180300D01*
X786400Y179000D01*
G01X779791Y182831D02*
Y179241D01*
X779200Y178650D01*
G01X792000Y232750D02*
X796500D01*
G01X800500D02*
X796500D01*
G01X800500D02*
X804000Y236250D01*
Y243500D01*
X803299Y244201D01*
X800080D01*
G01Y242231D02*
X794401D01*
X793901Y241731D01*
Y240141D01*
X793401Y239641D01*
X792401D01*
X791901Y240141D01*
Y245351D01*
X791401Y245851D01*
X790401D01*
X789901Y245351D01*
Y239659D01*
X789401Y239159D01*
X788401D01*
X787901Y239659D01*
Y245351D01*
X787401Y245851D01*
X786401D01*
X785901Y245351D01*
Y239597D01*
X785401Y239097D01*
X784401D01*
X783901Y239597D01*
Y245351D01*
X783401Y245851D01*
X782401D01*
X781901Y245351D01*
Y243385D01*
X781401Y242885D01*
X780401D01*
X779901Y243385D01*
Y245351D01*
X779401Y245851D01*
X778401D01*
X777901Y245351D01*
Y240391D01*
X777401Y239891D01*
X776401D01*
X775901Y240391D01*
Y245351D01*
X775401Y245851D01*
X774401D01*
X773901Y245351D01*
Y240432D01*
X773401Y239932D01*
X772401D01*
X771901Y240432D01*
Y245351D01*
X771401Y245851D01*
X770401D01*
X769901Y245351D01*
Y244369D01*
X769401Y243869D01*
X768401D01*
X767901Y244369D01*
Y246865D01*
X767401Y247365D01*
X766401D01*
X765901Y246865D01*
Y245261D01*
X765401Y244761D01*
X764401D01*
X763901Y245261D01*
Y246774D01*
X763401Y247274D01*
X759558D01*
G01X800080Y279636D02*
X793837D01*
G01X800080Y275696D02*
X793837D01*
G01X800080Y269791D02*
X789791D01*
X785976Y265976D01*
X782687D01*
X780837Y267826D01*
G01X784837Y263891D02*
X786767D01*
X788232Y265356D01*
X789215D01*
X789715Y264856D01*
Y261565D01*
X790215Y261065D01*
X791215D01*
X791715Y261565D01*
Y265356D01*
X792215Y265856D01*
X800080D01*
G01X784837Y259951D02*
X800080D01*
G01Y256011D02*
X793852D01*
G01X800080Y252076D02*
X793852D01*
G01X800080Y271761D02*
X793837D01*
G01X800080Y267826D02*
X793837D01*
G01Y263696D02*
X795617Y261916D01*
X800080D01*
G01X774657Y255999D02*
X775798Y257140D01*
X791752D01*
X792593Y257981D01*
X800080D01*
G01Y254046D02*
X767227D01*
X765638Y255635D01*
G01X774637Y251876D02*
X777734D01*
X778234Y251376D01*
Y250957D01*
X778734Y250457D01*
X779734D01*
X780234Y250957D01*
Y251546D01*
X780734Y252046D01*
X781734D01*
X782234Y251546D01*
Y250957D01*
X782734Y250457D01*
X783734D01*
X784234Y250957D01*
Y251546D01*
X784734Y252046D01*
X785734D01*
X786234Y251546D01*
Y250957D01*
X786734Y250457D01*
X787734D01*
X788234Y250957D01*
Y251546D01*
X788734Y252046D01*
X790021D01*
X791962Y250106D01*
X800080D01*
G01X784837Y271761D02*
X790742Y277666D01*
X800080D01*
G01X784837Y267826D02*
X790742Y273731D01*
X800080D01*
G01X793837Y287696D02*
X795992Y285541D01*
X800080D01*
G01Y281601D02*
X790677D01*
X780837Y271761D01*
G54D79*
X713712Y470871D03*
Y465871D03*
Y460871D03*
Y455871D03*
X733712D03*
Y460871D03*
Y465871D03*
Y470871D03*
G54D89*
G01X391424Y199526D02*
X391511D01*
X391936Y199101D01*
X394293D01*
X395344Y200152D01*
Y201880D01*
X396525Y203061D01*
X398497D01*
X399237Y203801D01*
Y209637D01*
X400650Y211050D01*
X402274D01*
X403176Y211952D01*
Y213577D01*
X404529Y214930D01*
X406196D01*
X407100Y215834D01*
Y217471D01*
G02X407512Y218468I1410J1D01*
G02X408509Y218880I996J-998D01*
G01X409099D01*
G03X409449Y219230I0J350D01*
G01Y220473D01*
G01X391424Y197926D02*
X391511D01*
X391936Y198351D01*
X394604D01*
X396094Y199841D01*
Y201569D01*
X396836Y202311D01*
X398808D01*
X399987Y203490D01*
Y209326D01*
X400961Y210300D01*
X402585D01*
X403926Y211641D01*
Y213266D01*
X404840Y214180D01*
X406507D01*
X407850Y215523D01*
Y217471D01*
G02X408043Y217937I659J0D01*
G02X408509Y218130I466J-466D01*
G01X409099D01*
G02X409449Y217780I0J-350D01*
G01Y216536D01*
G01X402190Y198582D02*
X402802D01*
X403170Y198950D01*
Y209652D01*
X404534Y211016D01*
X406216D01*
X407106Y211906D01*
Y213453D01*
X408510Y214857D01*
X410036D01*
X411037Y215858D01*
Y217471D01*
G02X411449Y218468I1410J1D01*
G02X412446Y218880I996J-998D01*
G01X413036D01*
G03X413386Y219230I0J350D01*
G01Y220473D01*
G01X388424Y211431D02*
X388511D01*
X388936Y211006D01*
X389893D01*
G03X390804Y211384I0J1287D01*
G01X390906Y211486D01*
G03X391386Y212643I-1157J1158D01*
G01Y216915D01*
G02X391961Y218305I1965J1D01*
G02X393351Y218880I1389J-1390D01*
G01X397288D01*
G03X397638Y219230I0J350D01*
G01Y220473D01*
G01X388424Y209831D02*
X388511D01*
X388936Y210256D01*
X389893D01*
G03X391335Y210854I0J2038D01*
G01X391437Y210955D01*
G03X392136Y212642I-1688J1688D01*
G01Y216916D01*
X392137Y216915D01*
G02X392491Y217774I1214J2D01*
G01X392492D01*
G02X393351Y218130I859J-858D01*
G01X397288D01*
G02X397638Y217780I0J-350D01*
G01Y216536D01*
G01X387893Y207563D02*
X387980D01*
X388405Y207138D01*
X390334D01*
X391280Y208084D01*
Y209541D01*
X392745Y211006D01*
X394308D01*
X395293Y211991D01*
Y213761D01*
X396391Y214859D01*
X398238D01*
X399226Y215847D01*
Y217471D01*
G02X399638Y218468I1410J1D01*
G02X400635Y218880I996J-998D01*
G01X401225D01*
G03X401575Y219230I0J350D01*
G01Y220473D01*
G01Y216536D02*
Y217780D01*
G03X401225Y218130I-350J0D01*
G01X400635D01*
G03X400169Y217937I0J-659D01*
G03X399976Y217471I466J-466D01*
G01Y215536D01*
X398549Y214109D01*
X396702D01*
X396043Y213450D01*
Y211680D01*
X394619Y210256D01*
X393056D01*
X392030Y209230D01*
Y207773D01*
X390645Y206388D01*
X388405D01*
X387980Y205963D01*
X387893D01*
G01X388433Y203643D02*
X388520D01*
X388945Y203218D01*
X390670D01*
X391343Y203891D01*
Y205685D01*
X392737Y207079D01*
X394511D01*
X395291Y207859D01*
Y209659D01*
X396691Y211059D01*
X398335D01*
X399338Y212062D01*
Y213555D01*
X400633Y214850D01*
X402166D01*
X403163Y215847D01*
Y217471D01*
G02X403575Y218468I1410J1D01*
G02X404572Y218880I996J-998D01*
G01X405162D01*
G03X405512Y219230I0J350D01*
G01Y220473D01*
G01X388433Y202043D02*
X388520D01*
X388945Y202468D01*
X390981D01*
X392093Y203580D01*
Y205374D01*
X393048Y206329D01*
X394822D01*
X396041Y207548D01*
Y209348D01*
X397002Y210309D01*
X398646D01*
X400088Y211751D01*
Y213244D01*
X400944Y214100D01*
X402477D01*
X403913Y215536D01*
Y217471D01*
G02X404106Y217937I659J0D01*
G02X404572Y218130I466J-466D01*
G01X405162D01*
G02X405512Y217780I0J-350D01*
G01Y216536D01*
G01X403355Y197484D02*
X403333Y197506D01*
Y198052D01*
X403920Y198639D01*
Y209341D01*
X404845Y210266D01*
X406527D01*
X407856Y211595D01*
Y213142D01*
X408821Y214107D01*
X410358D01*
X411787Y215536D01*
Y217471D01*
G02X411980Y217937I659J0D01*
G02X412446Y218130I466J-466D01*
G01X413036D01*
G02X413386Y217780I0J-350D01*
G01Y216536D01*
G01X405992Y197935D02*
X406615D01*
X407109Y198429D01*
Y209611D01*
X408548Y211050D01*
X410135D01*
X411046Y211961D01*
Y213577D01*
X412409Y214940D01*
X414077D01*
X414974Y215837D01*
Y217471D01*
G02X415386Y218468I1410J1D01*
G02X416383Y218880I996J-998D01*
G01X416973D01*
G03X417323Y219230I0J350D01*
G01Y220473D01*
G01X407124Y196804D02*
Y197383D01*
X407859Y198118D01*
Y209300D01*
X408859Y210300D01*
X410446D01*
X411796Y211650D01*
Y213266D01*
X412720Y214190D01*
X414388D01*
X415724Y215526D01*
Y217471D01*
G02X415917Y217937I659J0D01*
G02X416383Y218130I466J-466D01*
G01X416973D01*
G02X417323Y217780I0J-350D01*
G01Y216536D01*
G01X410729Y198786D02*
Y198873D01*
X411046Y199190D01*
Y209656D01*
X412408Y211018D01*
X414072D01*
X415050Y211996D01*
Y213586D01*
X416387Y214923D01*
X417976D01*
X418911Y215858D01*
Y217471D01*
G02X419323Y218468I1410J1D01*
G02X420320Y218880I996J-998D01*
G01X420910D01*
G03X421260Y219230I0J350D01*
G01Y220473D01*
G01X412329Y198786D02*
Y198873D01*
X411796Y199406D01*
Y209345D01*
X412719Y210268D01*
X414383D01*
X415800Y211685D01*
Y213275D01*
X416698Y214173D01*
X418298D01*
X419661Y215536D01*
Y217471D01*
G02X419854Y217937I659J0D01*
G02X420320Y218130I466J-466D01*
G01X420910D01*
G02X421260Y217780I0J-350D01*
G01Y216536D01*
G01X414753Y198248D02*
Y198335D01*
X414981Y198563D01*
Y209643D01*
X416388Y211050D01*
X417896D01*
X418850Y212004D01*
Y213498D01*
X420282Y214930D01*
X421985D01*
X422848Y215793D01*
Y217471D01*
G02X423260Y218468I1410J1D01*
G02X424257Y218880I996J-998D01*
G01X424847D01*
G03X425197Y219230I0J350D01*
G01Y220473D01*
G01X416353Y198248D02*
Y198335D01*
X415731Y198957D01*
Y209332D01*
X416699Y210300D01*
X418207D01*
X419600Y211693D01*
Y213187D01*
X420593Y214180D01*
X422296D01*
X423598Y215482D01*
Y217471D01*
G02X423791Y217937I659J0D01*
G02X424257Y218130I466J-466D01*
G01X424847D01*
G02X425197Y217780I0J-350D01*
G01Y216536D01*
G01X422557Y199567D02*
X422855Y199865D01*
Y213501D01*
X424300Y214946D01*
X426237D01*
X426785Y215494D01*
Y217471D01*
G02X427197Y218468I1410J1D01*
G02X428194Y218880I996J-998D01*
G01X428784D01*
G03X429134Y219230I0J350D01*
G01Y220473D01*
G01X424157Y199493D02*
X423605Y200045D01*
Y213190D01*
X424611Y214196D01*
X426548D01*
X427535Y215183D01*
Y217471D01*
G02X427728Y217937I659J0D01*
G02X428194Y218130I466J-466D01*
G01X428784D01*
G02X429134Y217780I0J-350D01*
G01Y216536D01*
G01X426511Y199344D02*
Y199431D01*
X426787Y199707D01*
Y210061D01*
X427737Y211011D01*
X429850D01*
X430736Y211897D01*
Y217507D01*
G02X431134Y218468I1359J0D01*
G02X432131Y218880I996J-998D01*
G01X432721D01*
G03X433071Y219230I0J350D01*
G01Y220473D01*
G01Y216536D02*
Y217780D01*
G03X432721Y218130I-350J0D01*
G01X432131D01*
G03X431665Y217937I0J-659D01*
G03X431486Y217505I432J-432D01*
G01Y211586D01*
X430161Y210261D01*
X428048D01*
X427537Y209750D01*
Y200005D01*
X428111Y199431D01*
Y199344D01*
G01X437008Y220473D02*
Y219230D01*
G02X436658Y218880I-350J0D01*
G01X436068D01*
G03X435071Y218468I-1J-1410D01*
G03X434662Y217481I986J-987D01*
G01Y207888D01*
X433844Y207070D01*
X432096D01*
X430730Y205704D01*
Y199624D01*
X430455Y199349D01*
Y199262D01*
G01X437008Y216536D02*
Y217780D01*
G03X436658Y218130I-350J0D01*
G01X436068D01*
G03X435602Y217937I0J-659D01*
G03X435412Y217478I459J-459D01*
G01Y207577D01*
X434155Y206320D01*
X432407D01*
X431480Y205393D01*
Y199924D01*
X432055Y199349D01*
Y199262D01*
G01X440945Y220473D02*
Y219230D01*
G02X440595Y218880I-350J0D01*
G01X440005D01*
G03X439008Y218468I-1J-1410D01*
G03X438609Y217505I963J-963D01*
G01Y199873D01*
X437488Y198752D01*
Y197543D01*
X437063Y197118D01*
Y197031D01*
G01X440945Y216536D02*
Y217780D01*
G03X440595Y218130I-350J0D01*
G01X440005D01*
G03X439539Y217937I0J-659D01*
G03X439359Y217502I435J-435D01*
G01Y199562D01*
X438238Y198441D01*
Y197543D01*
X438663Y197118D01*
Y197031D01*
G01X444882Y220473D02*
Y219230D01*
G02X444532Y218880I-350J0D01*
G01X443942D01*
G03X442945Y218468I-1J-1410D01*
G03X442536Y217481I986J-987D01*
G01Y199906D01*
X442138Y199508D01*
Y197543D01*
X441713Y197118D01*
Y197031D01*
G01X444882Y216536D02*
Y217780D01*
G03X444532Y218130I-350J0D01*
G01X443942D01*
G03X443476Y217937I0J-659D01*
G03X443286Y217478I459J-459D01*
G01Y199595D01*
X442888Y199197D01*
Y197543D01*
X443313Y197118D01*
Y197031D01*
G01X448819Y220473D02*
Y219230D01*
G02X448469Y218880I-350J0D01*
G01X447879D01*
G03X446882Y218468I-1J-1410D01*
G03X446483Y217505I963J-963D01*
G01Y199166D01*
X446058Y198741D01*
Y198654D01*
G01X448819Y216536D02*
Y217780D01*
G03X448469Y218130I-350J0D01*
G01X447879D01*
G03X447413Y217937I0J-659D01*
G03X447233Y217502I435J-435D01*
G01Y199166D01*
X447658Y198741D01*
Y198654D01*
G01X456693Y220473D02*
Y219230D01*
G02X456343Y218880I-350J0D01*
G01X455753D01*
G03X454756Y218468I-1J-1410D01*
G03X454291Y217345I1124J-1123D01*
G01Y204620D01*
X452020Y202348D01*
Y200667D01*
X451625Y200272D01*
Y200185D01*
G01X456693Y216536D02*
Y217780D01*
G03X456343Y218130I-350J0D01*
G01X455753D01*
G03X455287Y217937I0J-659D01*
G03X455041Y217343I594J-594D01*
G01Y204309D01*
X452770Y202037D01*
Y200727D01*
X453225Y200272D01*
Y200185D01*
G01X513700Y233300D02*
Y233387D01*
X514125Y233812D01*
Y236823D01*
X513387Y237562D01*
X513141Y237808D01*
X499021D01*
G02X497656Y239173I0J1365D01*
G01Y239765D01*
G03X497263Y240158I-393J0D01*
G01X496063D01*
G01X515300Y233300D02*
Y233387D01*
X514875Y233812D01*
Y237134D01*
X514163Y237847D01*
X513452Y238558D01*
X499021D01*
G02X498406Y239173I0J615D01*
G01Y239764D01*
G02X498800Y240158I394J0D01*
G01X500000D01*
G01X460630Y220473D02*
Y219230D01*
G02X460280Y218880I-350J0D01*
G01X459690D01*
G03X458693Y218468I-1J-1410D01*
G03X458285Y217483I985J-985D01*
G01Y199228D01*
X457953Y198896D01*
Y198809D01*
G01X460630Y216536D02*
Y217780D01*
G03X460280Y218130I-350J0D01*
G01X459690D01*
G03X459224Y217937I0J-659D01*
G03X459035Y217481I456J-456D01*
G01Y199414D01*
X459553Y198896D01*
Y198809D01*
G01X464567Y220473D02*
Y219230D01*
G02X464217Y218880I-350J0D01*
G01X463627D01*
G03X462630Y218468I-1J-1410D01*
G03X462222Y217483I985J-985D01*
G01Y198740D01*
X461844Y198362D01*
Y198275D01*
G01X464567Y216536D02*
Y217780D01*
G03X464217Y218130I-350J0D01*
G01X463627D01*
G03X463161Y217937I0J-659D01*
G03X462972Y217481I456J-456D01*
G01Y198834D01*
X463444Y198362D01*
Y198275D01*
G01X468504Y220473D02*
Y219230D01*
G02X468154Y218880I-350J0D01*
G01X467564D01*
G03X466567Y218468I-1J-1410D01*
G03X466159Y217483I985J-985D01*
G01Y198803D01*
X465734Y198378D01*
Y198291D01*
G01X468504Y216536D02*
Y217780D01*
G03X468154Y218130I-350J0D01*
G01X467564D01*
G03X467098Y217937I0J-659D01*
G03X466909Y217481I456J-456D01*
G01Y198803D01*
X467334Y198378D01*
Y198291D01*
G01X469666Y198741D02*
Y198828D01*
X470091Y199253D01*
Y217471D01*
G02X470504Y218468I1410J0D01*
G02X471501Y218880I996J-998D01*
G01X472091D01*
G03X472441Y219230I0J350D01*
G01Y220473D01*
G01Y216536D02*
Y217780D01*
G03X472091Y218130I-350J0D01*
G01X471501D01*
G03X471035Y217937I0J-659D01*
G03X470841Y217469I468J-468D01*
G01Y199253D01*
X471266Y198828D01*
Y198741D01*
G01X476378Y220473D02*
Y219230D01*
G02X476028Y218880I-350J0D01*
G01X475438D01*
G03X474441Y218468I-1J-1410D01*
G03X474040Y217500I968J-968D01*
G01Y198803D01*
X473615Y198378D01*
Y198291D01*
G01X476378Y216536D02*
Y217780D01*
G03X476028Y218130I-350J0D01*
G01X475438D01*
G03X474972Y217937I0J-659D01*
G03X474790Y217498I439J-439D01*
G01Y198803D01*
X475215Y198378D01*
Y198291D01*
G01X480315Y220473D02*
Y219230D01*
G02X479965Y218880I-350J0D01*
G01X479375D01*
G03X478378Y218468I-1J-1410D01*
G03X477974Y217493I975J-975D01*
G01Y198803D01*
X477549Y198378D01*
Y198291D01*
G01X480315Y216536D02*
Y217780D01*
G03X479965Y218130I-350J0D01*
G01X479375D01*
G03X478909Y217937I0J-659D01*
G03X478724Y217490I447J-447D01*
G01Y198803D01*
X479149Y198378D01*
Y198291D01*
G01X484252Y220473D02*
Y219230D01*
G02X483902Y218880I-350J0D01*
G01X483312D01*
G03X482315Y218468I-1J-1410D01*
G03X481908Y217485I984J-983D01*
G01Y198803D01*
X481483Y198378D01*
Y198291D01*
G01X484252Y216536D02*
Y217780D01*
G03X483902Y218130I-350J0D01*
G01X483312D01*
G03X482846Y217937I0J-659D01*
G03X482658Y217483I454J-454D01*
G01Y198803D01*
X483083Y198378D01*
Y198291D01*
G01X488189Y220473D02*
Y219230D01*
G02X487839Y218880I-350J0D01*
G01X487249D01*
G03X486252Y218468I-1J-1410D01*
G03X485839Y217471I997J-997D01*
G01Y199600D01*
X488077Y197362D01*
Y197075D01*
X488139Y197013D01*
G01X488189Y216536D02*
Y217780D01*
G03X487839Y218130I-350J0D01*
G01X487249D01*
G03X486783Y217937I0J-659D01*
G03X486589Y217469I468J-468D01*
G01Y199911D01*
X488294Y198206D01*
X489209D01*
X489270Y198145D01*
G01X517860Y252906D02*
X517773D01*
X517118Y253561D01*
X499016D01*
G02X497656Y254921I0J1360D01*
G01Y255513D01*
G03X497263Y255906I-393J0D01*
G01X496063D01*
G01X517860Y254506D02*
X517772D01*
X517577Y254311D01*
X499016D01*
G02X498406Y254921I0J610D01*
G01Y255512D01*
G02X498800Y255906I394J0D01*
G01X500000D01*
G01X517296Y257251D02*
X517209D01*
X516954Y257506D01*
X499008D01*
G02X497656Y258858I0J1352D01*
G01Y259450D01*
G03X497263Y259843I-393J0D01*
G01X496063D01*
G01X517296Y258851D02*
X517209D01*
X516614Y258256D01*
X499008D01*
G02X498406Y258858I0J602D01*
G01Y259449D01*
G02X498800Y259843I394J0D01*
G01X500000D01*
G01X513272Y265023D02*
X513185D01*
X512837Y265371D01*
X499017D01*
G02X497656Y266732I0J1361D01*
G01Y267324D01*
G03X497263Y267717I-393J0D01*
G01X496063D01*
G01X513272Y266623D02*
X513185D01*
X512683Y266121D01*
X499017D01*
G02X498406Y266732I0J611D01*
G01Y267323D01*
G02X498800Y267717I394J0D01*
G01X500000D01*
G01X517622Y240424D02*
X517561Y240485D01*
Y241115D01*
X516930Y241746D01*
X499020D01*
G02X497656Y243110I0J1364D01*
G01Y243702D01*
G03X497263Y244095I-393J0D01*
G01X496063D01*
G01X500000D02*
X498800D01*
G03X498406Y243701I0J-394D01*
G01Y243110D01*
G03X499020Y242496I614J0D01*
G01X517241D01*
X518121Y241616D01*
X518693D01*
X518754Y241555D01*
G01X517093Y268883D02*
X517006D01*
X516581Y269308D01*
X499017D01*
G02X497656Y270669I0J1361D01*
G01Y271261D01*
G03X497263Y271654I-393J0D01*
G01X496063D01*
G01X517093Y270483D02*
X517006D01*
X516581Y270058D01*
X499017D01*
G02X498406Y270669I0J611D01*
G01Y271260D01*
G02X498800Y271654I394J0D01*
G01X500000D01*
G01X496063Y248032D02*
X497263D01*
G02X497656Y247639I0J-393D01*
G01Y247047D01*
G03X499022Y245681I1366J0D01*
G01X518193D01*
X518462Y245412D01*
Y244812D01*
X518523Y244751D01*
G01X500000Y248032D02*
X498800D01*
G03X498406Y247638I0J-394D01*
G01Y247047D01*
G03X499022Y246431I616J0D01*
G01X518504D01*
X518992Y245943D01*
X519594D01*
X519655Y245882D01*
G01X517978Y248932D02*
X517891D01*
X517201Y249622D01*
X499018D01*
G02X497656Y250984I0J1362D01*
G01Y251576D01*
G03X497263Y251969I-393J0D01*
G01X496063D01*
G01X517978Y250532D02*
X517891D01*
X517731Y250372D01*
X499018D01*
G02X498406Y250984I0J612D01*
G01Y251575D01*
G02X498800Y251969I394J0D01*
G01X500000D01*
G01X517430Y272864D02*
X517343D01*
X516964Y273243D01*
X499019D01*
G02X497656Y274606I0J1363D01*
G01Y275198D01*
G03X497263Y275591I-393J0D01*
G01X496063D01*
G01X517430Y274464D02*
X517343D01*
X516872Y273993D01*
X499019D01*
G02X498406Y274606I0J613D01*
G01Y275197D01*
G02X498800Y275591I394J0D01*
G01X500000D01*
G01X518737Y276764D02*
X518650D01*
X518225Y277189D01*
X499010D01*
G02X497656Y278543I0J1354D01*
G01Y279135D01*
G03X497263Y279528I-393J0D01*
G01X496063D01*
G01X518737Y278364D02*
X518650D01*
X518225Y277939D01*
X499010D01*
G02X498406Y278543I0J604D01*
G01Y279134D01*
G02X498800Y279528I394J0D01*
G01X500000D01*
G01X516965Y280828D02*
X516878D01*
X516577Y281129D01*
X499007D01*
G02X497656Y282480I0J1351D01*
G01Y283072D01*
G03X497263Y283465I-393J0D01*
G01X496063D01*
G01X516965Y282428D02*
X516878D01*
X516329Y281879D01*
X499007D01*
G02X498406Y282480I0J601D01*
G01Y283071D01*
G02X498800Y283465I394J0D01*
G01X500000D01*
G01X516975Y284679D02*
X516888D01*
X516509Y285058D01*
X499015D01*
G02X497656Y286417I0J1359D01*
G01Y287009D01*
G03X497263Y287402I-393J0D01*
G01X496063D01*
G01X516975Y286279D02*
X516888D01*
X516417Y285808D01*
X499015D01*
G02X498406Y286417I0J609D01*
G01Y287008D01*
G02X498800Y287402I394J0D01*
G01X500000D01*
G01X496063Y299213D02*
X497306D01*
G03X497656Y299563I0J350D01*
G01Y300098D01*
G02X499101Y301543I1445J0D01*
G01X509154D01*
X509403Y301792D01*
X509490D01*
G01X500000Y299213D02*
X498756D01*
G02X498406Y299563I0J350D01*
G01Y300098D01*
G02X499101Y300793I695J0D01*
G01X508802D01*
X509403Y300192D01*
X509490D01*
G01X510540Y292737D02*
X510453D01*
X510233Y292517D01*
X507016D01*
X505847Y293686D01*
X499303D01*
G03X497656Y292039I0J-1647D01*
G01Y291689D01*
G02X497306Y291339I-350J0D01*
G01X496063D01*
G01X510540Y291137D02*
X510453D01*
X509823Y291767D01*
X506705D01*
X505536Y292936D01*
X499303D01*
G03X498406Y292039I0J-897D01*
G01Y291689D01*
G03X498756Y291339I350J0D01*
G01X500000D01*
G01X509757Y297845D02*
X509670D01*
X509436Y297611D01*
X499106D01*
G03X497656Y296161I0J-1450D01*
G01Y295626D01*
G02X497306Y295276I-350J0D01*
G01X496063D01*
G01X509757Y296245D02*
X509670D01*
X509054Y296861D01*
X499106D01*
G03X498406Y296161I0J-700D01*
G01Y295626D01*
G03X498756Y295276I350J0D01*
G01X500000D01*
G01X510414Y305323D02*
X510327D01*
X510093Y305089D01*
X509160D01*
X508753Y305496D01*
X498876D01*
G03X497656Y304276I0J-1220D01*
G01Y303500D01*
G02X497306Y303150I-350J0D01*
G01X496063D01*
G01X510414Y303723D02*
X510327D01*
X509711Y304339D01*
X508849D01*
X508442Y304746D01*
X498876D01*
G03X498406Y304276I0J-470D01*
G01Y303500D01*
G03X498756Y303150I350J0D01*
G01X500000D01*
G01X669018Y112786D02*
X668957Y112725D01*
M02*
